FILE_TYPE = MACRO_DRAWING;
SET COLOR_WIRE YELLOW;
SET COLOR_PROP ORANGE;
SET COLOR_DOT WHITE;
SET COLOR_ARC YELLOW;
SET COLOR_BODY GREEN;
SET COLOR_NOTE PURPLE;
SET PROP_DISPLAY VALUE;
SET PAGE_NUMBER P80;
FORCEADD OFFPAGE..6
R 2
(-2225 5850);
FORCEPROP 2 LAST $XR0 118 
J 0
(-2011 5850);
DISPLAY 0.638298 (-2011 5850);
PAINT MONO (-2011 5850);
FORCEPROP 2 LAST CDS_LIB standard
J 0
(-2225 5850);
DISPLAY INVISIBLE (-2225 5850);
FORCEPROP 2 LAST PATH I1891
J 0
(-2000 5900);
DISPLAY 0.680851 (-2000 5900);
DISPLAY INVISIBLE (-2000 5900);
FORCEPROP 1 LAST OFFPAGE TRUE
J 2
(-2550 5725);
DISPLAY 0.872340 (-2550 5725);
PAINT GREEN (-2550 5725);
DISPLAY INVISIBLE (-2550 5725);
FORCEPROP 1 LAST COMMENT_BODY TRUE
J 2
(-2325 5775);
DISPLAY 0.872340 (-2325 5775);
PAINT GREEN (-2325 5775);
DISPLAY INVISIBLE (-2325 5775);
FORCEADD OFFPAGE..1
R 2
(-2225 5800);
FORCEPROP 2 LAST $XR0 161 
J 0
(-2039 5800);
DISPLAY 0.638298 (-2039 5800);
PAINT MONO (-2039 5800);
FORCEPROP 1 LAST COMMENT_BODY TRUE
J 2
(-2350 5700);
DISPLAY 0.872340 (-2350 5700);
PAINT GREEN (-2350 5700);
DISPLAY INVISIBLE (-2350 5700);
FORCEPROP 1 LAST OFFPAGE TRUE
J 2
(-2550 5675);
DISPLAY 0.872340 (-2550 5675);
PAINT GREEN (-2550 5675);
DISPLAY INVISIBLE (-2550 5675);
FORCEPROP 2 LAST CDS_LIB standard
J 0
(-2225 5800);
DISPLAY INVISIBLE (-2225 5800);
FORCEPROP 2 LAST PATH I1892
J 0
(-2025 5850);
DISPLAY 0.680851 (-2025 5850);
DISPLAY INVISIBLE (-2025 5850);
FORCEADD OFFPAGE..1
R 2
(-2225 5900);
FORCEPROP 2 LAST $XR0 118 
J 0
(-2039 5900);
DISPLAY 0.638298 (-2039 5900);
PAINT MONO (-2039 5900);
FORCEPROP 1 LAST COMMENT_BODY TRUE
J 2
(-2350 5800);
DISPLAY 0.872340 (-2350 5800);
PAINT GREEN (-2350 5800);
DISPLAY INVISIBLE (-2350 5800);
FORCEPROP 1 LAST OFFPAGE TRUE
J 2
(-2550 5775);
DISPLAY 0.872340 (-2550 5775);
PAINT GREEN (-2550 5775);
DISPLAY INVISIBLE (-2550 5775);
FORCEPROP 2 LAST CDS_LIB standard
J 0
(-2225 5900);
DISPLAY INVISIBLE (-2225 5900);
FORCEPROP 2 LAST PATH I1893
J 0
(-2025 5950);
DISPLAY 0.680851 (-2025 5950);
DISPLAY INVISIBLE (-2025 5950);
FORCEADD OFFPAGE..1
R 2
(-2225 5950);
FORCEPROP 2 LAST $XR0 28 
J 0
(-2039 5950);
DISPLAY 0.638298 (-2039 5950);
PAINT MONO (-2039 5950);
FORCEPROP 1 LAST COMMENT_BODY TRUE
J 2
(-2350 5850);
DISPLAY 0.872340 (-2350 5850);
PAINT GREEN (-2350 5850);
DISPLAY INVISIBLE (-2350 5850);
FORCEPROP 1 LAST OFFPAGE TRUE
J 2
(-2550 5825);
DISPLAY 0.872340 (-2550 5825);
PAINT GREEN (-2550 5825);
DISPLAY INVISIBLE (-2550 5825);
FORCEPROP 2 LAST CDS_LIB standard
J 0
(-2225 5950);
DISPLAY INVISIBLE (-2225 5950);
FORCEPROP 2 LAST PATH I1894
J 0
(-2025 6000);
DISPLAY 0.680851 (-2025 6000);
DISPLAY INVISIBLE (-2025 6000);
FORCEADD OFFPAGE..2
(-2225 6000);
FORCEPROP 2 LAST $XR0 143 
J 0
(-2036 6000);
DISPLAY 0.638298 (-2036 6000);
PAINT MONO (-2036 6000);
FORCEPROP 1 LAST COMMENT_BODY TRUE
J 0
(-2270 5905);
DISPLAY 0.872340 (-2270 5905);
PAINT GREEN (-2270 5905);
DISPLAY INVISIBLE (-2270 5905);
FORCEPROP 1 LAST OFFPAGE TRUE
J 0
(-1900 5875);
DISPLAY 0.872340 (-1900 5875);
PAINT GREEN (-1900 5875);
DISPLAY INVISIBLE (-1900 5875);
FORCEPROP 2 LAST CDS_LIB standard
J 0
(-2225 6000);
DISPLAY INVISIBLE (-2225 6000);
FORCEPROP 2 LAST PATH I1895
J 0
(-2025 6050);
DISPLAY 0.680851 (-2025 6050);
DISPLAY INVISIBLE (-2025 6050);
FORCEADD OFFPAGE..1
R 2
(-2225 5750);
FORCEPROP 2 LAST $XR0 55 
J 0
(-2039 5750);
DISPLAY 0.638298 (-2039 5750);
PAINT MONO (-2039 5750);
FORCEPROP 1 LAST COMMENT_BODY TRUE
J 2
(-2350 5650);
DISPLAY 0.872340 (-2350 5650);
PAINT GREEN (-2350 5650);
DISPLAY INVISIBLE (-2350 5650);
FORCEPROP 1 LAST OFFPAGE TRUE
J 2
(-2550 5625);
DISPLAY 0.872340 (-2550 5625);
PAINT GREEN (-2550 5625);
DISPLAY INVISIBLE (-2550 5625);
FORCEPROP 2 LAST CDS_LIB standard
J 0
(-2225 5750);
DISPLAY INVISIBLE (-2225 5750);
FORCEPROP 2 LAST PATH I1896
J 0
(-2025 5800);
DISPLAY 0.680851 (-2025 5800);
DISPLAY INVISIBLE (-2025 5800);
FORCEADD Q_RES..1
(-3150 6000);
FORCEPROP 1 LAST LOCATION R933
J 0
(-3025 6000);
DISPLAY 0.489362 (-3025 6000);
PAINT SKYBLUE (-3025 6000);
FORCEPROP 0 LAST $SEC 1
J 2
(-3025 6050);
DISPLAY 0.680851 (-3025 6050);
PAINT MONO (-3025 6050);
DISPLAY INVISIBLE (-3025 6050);
FORCEPROP 0 LAST CDS_SEC 1
J 2
(-3025 6050);
DISPLAY 1.021277 (-3025 6050);
DISPLAY INVISIBLE (-3025 6050);
FORCEPROP 1 LASTPIN (-3250 6000) $PN 1
J 0
(-3238 6012);
DISPLAY 0.489362 (-3238 6012);
PAINT MONO (-3238 6012);
FORCEPROP 1 LASTPIN (-3050 6000) $PN 2
J 0
(-3088 6012);
DISPLAY 0.489362 (-3088 6012);
PAINT MONO (-3088 6012);
FORCEPROP 1 LAST VALUE 33
J 2
(-3275 6000);
DISPLAY 0.489362 (-3275 6000);
PAINT SKYBLUE (-3275 6000);
FORCEPROP 2 LAST ROOM RST_CPU0_PLD_TO_DIMM
J 2
(-3125 6100);
DISPLAY 0.744681 (-3125 6100);
PAINT RED (-3125 6100);
DISPLAY INVISIBLE (-3125 6100);
FORCEPROP 1 LAST PACK_TYPE 0402LF
J 2
(-2975 5925);
DISPLAY 0.489362 (-2975 5925);
PAINT SKYBLUE (-2975 5925);
DISPLAY INVISIBLE (-2975 5925);
FORCEPROP 1 LAST PART_NUMBER CS03302JB29
J 2
(-3050 6050);
DISPLAY 0.489362 (-3050 6050);
PAINT SKYBLUE (-3050 6050);
DISPLAY INVISIBLE (-3050 6050);
FORCEPROP 1 LAST TOLERANCE 5%
J 0
(-3275 5975);
DISPLAY 0.489362 (-3275 5975);
PAINT SKYBLUE (-3275 5975);
DISPLAY INVISIBLE (-3275 5975);
FORCEPROP 1 LAST MATERIAL CHIP
J 2
(-2975 5975);
DISPLAY 0.489362 (-2975 5975);
PAINT SKYBLUE (-2975 5975);
DISPLAY INVISIBLE (-2975 5975);
FORCEPROP 1 LAST WATTAGE 1/16W
J 2
(-3225 5925);
DISPLAY 0.489362 (-3225 5925);
PAINT SKYBLUE (-3225 5925);
DISPLAY INVISIBLE (-3225 5925);
FORCEPROP 1 LAST PATH I1897
J 0
(-3200 6150);
DISPLAY 0.978723 (-3200 6150);
PAINT WHITE (-3200 6150);
DISPLAY INVISIBLE (-3200 6150);
FORCEPROP 2 LAST BOM_COST MEM
J 2
(-3125 6150);
DISPLAY 0.744681 (-3125 6150);
PAINT WHITE (-3125 6150);
DISPLAY INVISIBLE (-3125 6150);
FORCEPROP 2 LAST CDS_LIB pure_quanta
J 2
(-3150 6000);
DISPLAY INVISIBLE (-3150 6000);
FORCEADD Q_RES..1
(-3150 5950);
FORCEPROP 1 LAST LOCATION R250
J 0
(-3025 5950);
DISPLAY 0.489362 (-3025 5950);
PAINT SKYBLUE (-3025 5950);
FORCEPROP 0 LAST $SEC 1
J 2
(-3025 6000);
DISPLAY 0.680851 (-3025 6000);
PAINT MONO (-3025 6000);
DISPLAY INVISIBLE (-3025 6000);
FORCEPROP 0 LAST CDS_SEC 1
J 2
(-3025 6000);
DISPLAY 1.021277 (-3025 6000);
DISPLAY INVISIBLE (-3025 6000);
FORCEPROP 1 LASTPIN (-3250 5950) $PN 1
J 0
(-3238 5962);
DISPLAY 0.489362 (-3238 5962);
PAINT MONO (-3238 5962);
FORCEPROP 1 LASTPIN (-3050 5950) $PN 2
J 0
(-3088 5962);
DISPLAY 0.489362 (-3088 5962);
PAINT MONO (-3088 5962);
FORCEPROP 1 LAST VALUE 0
J 2
(-3275 5950);
DISPLAY 0.489362 (-3275 5950);
PAINT SKYBLUE (-3275 5950);
FORCEPROP 2 LAST ROOM RST_CPU0_PLD_TO_DIMM
J 2
(-3125 6050);
DISPLAY 0.744681 (-3125 6050);
PAINT RED (-3125 6050);
DISPLAY INVISIBLE (-3125 6050);
FORCEPROP 1 LAST PACK_TYPE 0402LF
J 2
(-2975 5875);
DISPLAY 0.489362 (-2975 5875);
PAINT SKYBLUE (-2975 5875);
DISPLAY INVISIBLE (-2975 5875);
FORCEPROP 1 LAST PART_NUMBER CS00002JB38
J 2
(-3050 6000);
DISPLAY 0.489362 (-3050 6000);
PAINT SKYBLUE (-3050 6000);
DISPLAY INVISIBLE (-3050 6000);
FORCEPROP 1 LAST TOLERANCE 5%
J 0
(-3275 5925);
DISPLAY 0.489362 (-3275 5925);
PAINT SKYBLUE (-3275 5925);
DISPLAY INVISIBLE (-3275 5925);
FORCEPROP 1 LAST MATERIAL CHIP
J 2
(-2975 5925);
DISPLAY 0.489362 (-2975 5925);
PAINT SKYBLUE (-2975 5925);
DISPLAY INVISIBLE (-2975 5925);
FORCEPROP 1 LAST WATTAGE 1/16W
J 2
(-3225 5875);
DISPLAY 0.489362 (-3225 5875);
PAINT SKYBLUE (-3225 5875);
DISPLAY INVISIBLE (-3225 5875);
FORCEPROP 1 LAST PATH I1898
J 0
(-3200 6100);
DISPLAY 0.978723 (-3200 6100);
PAINT WHITE (-3200 6100);
DISPLAY INVISIBLE (-3200 6100);
FORCEPROP 2 LAST BOM_COST MEM
J 2
(-3125 6100);
DISPLAY 0.744681 (-3125 6100);
PAINT WHITE (-3125 6100);
DISPLAY INVISIBLE (-3125 6100);
FORCEPROP 2 LAST CDS_LIB pure_quanta
J 2
(-3150 5950);
DISPLAY INVISIBLE (-3150 5950);
FORCEADD Q_RES..1
(-3150 5750);
FORCEPROP 1 LAST LOCATION R193
J 0
(-3025 5750);
DISPLAY 0.489362 (-3025 5750);
PAINT SKYBLUE (-3025 5750);
FORCEPROP 0 LAST $SEC 1
J 2
(-3025 5800);
DISPLAY 0.680851 (-3025 5800);
PAINT MONO (-3025 5800);
DISPLAY INVISIBLE (-3025 5800);
FORCEPROP 0 LAST CDS_SEC 1
J 2
(-3025 5800);
DISPLAY 1.021277 (-3025 5800);
DISPLAY INVISIBLE (-3025 5800);
FORCEPROP 1 LASTPIN (-3250 5750) $PN 1
J 0
(-3238 5762);
DISPLAY 0.489362 (-3238 5762);
PAINT MONO (-3238 5762);
FORCEPROP 1 LASTPIN (-3050 5750) $PN 2
J 0
(-3088 5762);
DISPLAY 0.489362 (-3088 5762);
PAINT MONO (-3088 5762);
FORCEPROP 1 LAST VALUE 0
J 2
(-3275 5750);
DISPLAY 0.489362 (-3275 5750);
PAINT SKYBLUE (-3275 5750);
FORCEPROP 2 LAST ROOM RST_CPU0_PLD_TO_DIMM
J 2
(-3125 5850);
DISPLAY 0.744681 (-3125 5850);
PAINT RED (-3125 5850);
DISPLAY INVISIBLE (-3125 5850);
FORCEPROP 1 LAST PACK_TYPE 0402LF
J 2
(-2975 5675);
DISPLAY 0.489362 (-2975 5675);
PAINT SKYBLUE (-2975 5675);
DISPLAY INVISIBLE (-2975 5675);
FORCEPROP 1 LAST PART_NUMBER CS00002JB38
J 2
(-3050 5800);
DISPLAY 0.489362 (-3050 5800);
PAINT SKYBLUE (-3050 5800);
DISPLAY INVISIBLE (-3050 5800);
FORCEPROP 1 LAST TOLERANCE 5%
J 0
(-3275 5725);
DISPLAY 0.489362 (-3275 5725);
PAINT SKYBLUE (-3275 5725);
DISPLAY INVISIBLE (-3275 5725);
FORCEPROP 1 LAST MATERIAL CHIP
J 2
(-2975 5725);
DISPLAY 0.489362 (-2975 5725);
PAINT SKYBLUE (-2975 5725);
DISPLAY INVISIBLE (-2975 5725);
FORCEPROP 1 LAST WATTAGE 1/16W
J 2
(-3225 5675);
DISPLAY 0.489362 (-3225 5675);
PAINT SKYBLUE (-3225 5675);
DISPLAY INVISIBLE (-3225 5675);
FORCEPROP 1 LAST PATH I1899
J 0
(-3200 5900);
DISPLAY 0.978723 (-3200 5900);
PAINT WHITE (-3200 5900);
DISPLAY INVISIBLE (-3200 5900);
FORCEPROP 2 LAST BOM_COST MEM
J 2
(-3125 5900);
DISPLAY 0.744681 (-3125 5900);
PAINT WHITE (-3125 5900);
DISPLAY INVISIBLE (-3125 5900);
FORCEPROP 2 LAST CDS_LIB pure_quanta
J 2
(-3150 5750);
DISPLAY INVISIBLE (-3150 5750);
FORCEADD OFFPAGE..1
R 2
(-2225 5650);
FORCEPROP 2 LAST $XR0 161 
J 0
(-2039 5650);
DISPLAY 0.638298 (-2039 5650);
PAINT MONO (-2039 5650);
FORCEPROP 1 LAST COMMENT_BODY TRUE
J 2
(-2350 5550);
DISPLAY 0.872340 (-2350 5550);
PAINT GREEN (-2350 5550);
DISPLAY INVISIBLE (-2350 5550);
FORCEPROP 1 LAST OFFPAGE TRUE
J 2
(-2550 5525);
DISPLAY 0.872340 (-2550 5525);
PAINT GREEN (-2550 5525);
DISPLAY INVISIBLE (-2550 5525);
FORCEPROP 2 LAST CDS_LIB standard
J 0
(-2225 5650);
DISPLAY INVISIBLE (-2225 5650);
FORCEPROP 2 LAST PATH I1900
J 0
(-2025 5700);
DISPLAY 0.680851 (-2025 5700);
DISPLAY INVISIBLE (-2025 5700);
FORCEADD OFFPAGE..1
R 2
(-2225 5700);
FORCEPROP 2 LAST $XR0 210 
J 0
(-2039 5700);
DISPLAY 0.638298 (-2039 5700);
PAINT MONO (-2039 5700);
FORCEPROP 1 LAST COMMENT_BODY TRUE
J 2
(-2350 5600);
DISPLAY 0.872340 (-2350 5600);
PAINT GREEN (-2350 5600);
DISPLAY INVISIBLE (-2350 5600);
FORCEPROP 1 LAST OFFPAGE TRUE
J 2
(-2550 5575);
DISPLAY 0.872340 (-2550 5575);
PAINT GREEN (-2550 5575);
DISPLAY INVISIBLE (-2550 5575);
FORCEPROP 2 LAST CDS_LIB standard
J 0
(-2225 5700);
DISPLAY INVISIBLE (-2225 5700);
FORCEPROP 2 LAST PATH I1901
J 0
(-2025 5750);
DISPLAY 0.680851 (-2025 5750);
DISPLAY INVISIBLE (-2025 5750);
FORCEADD OFFPAGE..1
R 2
(-2225 5500);
FORCEPROP 2 LAST $XR0 160 
J 0
(-2039 5500);
DISPLAY 0.638298 (-2039 5500);
PAINT MONO (-2039 5500);
FORCEPROP 1 LAST OFFPAGE TRUE
J 2
(-2550 5375);
DISPLAY 0.872340 (-2550 5375);
PAINT GREEN (-2550 5375);
DISPLAY INVISIBLE (-2550 5375);
FORCEPROP 1 LAST COMMENT_BODY TRUE
J 2
(-2350 5400);
DISPLAY 0.872340 (-2350 5400);
PAINT GREEN (-2350 5400);
DISPLAY INVISIBLE (-2350 5400);
FORCEPROP 2 LAST PATH I1902
J 0
(-2025 5550);
DISPLAY 0.680851 (-2025 5550);
DISPLAY INVISIBLE (-2025 5550);
FORCEPROP 2 LAST CDS_LIB standard
J 0
(-2225 5500);
DISPLAY INVISIBLE (-2225 5500);
FORCEADD OFFPAGE..1
R 2
(-2225 5550);
FORCEPROP 2 LAST $XR0 149 
J 0
(-2039 5550);
DISPLAY 0.638298 (-2039 5550);
PAINT MONO (-2039 5550);
FORCEPROP 1 LAST COMMENT_BODY TRUE
J 2
(-2350 5450);
DISPLAY 0.872340 (-2350 5450);
PAINT GREEN (-2350 5450);
DISPLAY INVISIBLE (-2350 5450);
FORCEPROP 1 LAST OFFPAGE TRUE
J 2
(-2550 5425);
DISPLAY 0.872340 (-2550 5425);
PAINT GREEN (-2550 5425);
DISPLAY INVISIBLE (-2550 5425);
FORCEPROP 2 LAST CDS_LIB standard
J 0
(-2225 5550);
DISPLAY INVISIBLE (-2225 5550);
FORCEPROP 2 LAST PATH I1903
J 0
(-2025 5600);
DISPLAY 0.680851 (-2025 5600);
DISPLAY INVISIBLE (-2025 5600);
FORCEADD OFFPAGE..2
(-2225 5600);
FORCEPROP 2 LAST $XR2 142 
J 0
(-1826 5600);
DISPLAY 0.638298 (-1826 5600);
PAINT MONO (-1826 5600);
FORCEPROP 2 LAST $XR1 28 
J 0
(-1916 5600);
DISPLAY 0.638298 (-1916 5600);
PAINT MONO (-1916 5600);
FORCEPROP 2 LAST $XR0 144 
J 0
(-2036 5600);
DISPLAY 0.638298 (-2036 5600);
PAINT MONO (-2036 5600);
FORCEPROP 1 LAST COMMENT_BODY TRUE
J 0
(-2270 5505);
DISPLAY 0.872340 (-2270 5505);
PAINT GREEN (-2270 5505);
DISPLAY INVISIBLE (-2270 5505);
FORCEPROP 1 LAST OFFPAGE TRUE
J 0
(-1900 5475);
DISPLAY 0.872340 (-1900 5475);
PAINT GREEN (-1900 5475);
DISPLAY INVISIBLE (-1900 5475);
FORCEPROP 2 LAST CDS_LIB standard
J 0
(-2225 5600);
DISPLAY INVISIBLE (-2225 5600);
FORCEPROP 2 LAST PATH I1904
J 0
(-1825 5650);
DISPLAY 0.680851 (-1825 5650);
DISPLAY INVISIBLE (-1825 5650);
FORCEADD OFFPAGE..1
R 2
(-2225 5450);
FORCEPROP 2 LAST $XR0 159 
J 0
(-2039 5450);
DISPLAY 0.638298 (-2039 5450);
PAINT MONO (-2039 5450);
FORCEPROP 1 LAST COMMENT_BODY TRUE
J 2
(-2350 5350);
DISPLAY 0.872340 (-2350 5350);
PAINT GREEN (-2350 5350);
DISPLAY INVISIBLE (-2350 5350);
FORCEPROP 1 LAST OFFPAGE TRUE
J 2
(-2550 5325);
DISPLAY 0.872340 (-2550 5325);
PAINT GREEN (-2550 5325);
DISPLAY INVISIBLE (-2550 5325);
FORCEPROP 2 LAST PATH I1906
J 0
(-2025 5500);
DISPLAY 0.680851 (-2025 5500);
DISPLAY INVISIBLE (-2025 5500);
FORCEPROP 2 LAST CDS_LIB standard
J 0
(-2225 5450);
DISPLAY INVISIBLE (-2225 5450);
FORCEADD OFFPAGE..2
(-2225 4750);
FORCEPROP 2 LAST $XR0 55 
J 0
(-2036 4750);
DISPLAY 0.638298 (-2036 4750);
PAINT MONO (-2036 4750);
FORCEPROP 2 LAST CDS_LIB standard
J 0
(-2225 4750);
DISPLAY INVISIBLE (-2225 4750);
FORCEPROP 1 LAST OFFPAGE TRUE
J 0
(-1900 4625);
DISPLAY 0.872340 (-1900 4625);
PAINT GREEN (-1900 4625);
DISPLAY INVISIBLE (-1900 4625);
FORCEPROP 1 LAST COMMENT_BODY TRUE
J 0
(-2270 4655);
DISPLAY 0.872340 (-2270 4655);
PAINT GREEN (-2270 4655);
DISPLAY INVISIBLE (-2270 4655);
FORCEPROP 2 LAST PATH I1912
J 0
(-2025 4800);
DISPLAY 0.680851 (-2025 4800);
DISPLAY INVISIBLE (-2025 4800);
FORCEADD Q_RES..1
(-3150 5550);
FORCEPROP 1 LAST LOCATION R258
J 0
(-3025 5550);
DISPLAY 0.489362 (-3025 5550);
PAINT SKYBLUE (-3025 5550);
FORCEPROP 0 LAST $SEC 1
J 2
(-3025 5600);
DISPLAY 0.680851 (-3025 5600);
PAINT MONO (-3025 5600);
DISPLAY INVISIBLE (-3025 5600);
FORCEPROP 0 LAST CDS_SEC 1
J 2
(-3025 5600);
DISPLAY 1.021277 (-3025 5600);
DISPLAY INVISIBLE (-3025 5600);
FORCEPROP 1 LASTPIN (-3250 5550) $PN 1
J 0
(-3238 5562);
DISPLAY 0.489362 (-3238 5562);
PAINT MONO (-3238 5562);
FORCEPROP 1 LASTPIN (-3050 5550) $PN 2
J 0
(-3088 5562);
DISPLAY 0.489362 (-3088 5562);
PAINT MONO (-3088 5562);
FORCEPROP 1 LAST VALUE 0
J 2
(-3275 5550);
DISPLAY 0.489362 (-3275 5550);
PAINT SKYBLUE (-3275 5550);
FORCEPROP 2 LAST ROOM RST_CPU0_PLD_TO_DIMM
J 2
(-3125 5650);
DISPLAY 0.744681 (-3125 5650);
PAINT RED (-3125 5650);
DISPLAY INVISIBLE (-3125 5650);
FORCEPROP 1 LAST PACK_TYPE 0402LF
J 2
(-2975 5475);
DISPLAY 0.489362 (-2975 5475);
PAINT SKYBLUE (-2975 5475);
DISPLAY INVISIBLE (-2975 5475);
FORCEPROP 1 LAST PART_NUMBER CS00002JB38
J 2
(-3050 5600);
DISPLAY 0.489362 (-3050 5600);
PAINT SKYBLUE (-3050 5600);
DISPLAY INVISIBLE (-3050 5600);
FORCEPROP 1 LAST TOLERANCE 5%
J 0
(-3275 5525);
DISPLAY 0.489362 (-3275 5525);
PAINT SKYBLUE (-3275 5525);
DISPLAY INVISIBLE (-3275 5525);
FORCEPROP 1 LAST MATERIAL CHIP
J 2
(-2975 5525);
DISPLAY 0.489362 (-2975 5525);
PAINT SKYBLUE (-2975 5525);
DISPLAY INVISIBLE (-2975 5525);
FORCEPROP 1 LAST WATTAGE 1/16W
J 2
(-3225 5475);
DISPLAY 0.489362 (-3225 5475);
PAINT SKYBLUE (-3225 5475);
DISPLAY INVISIBLE (-3225 5475);
FORCEPROP 1 LAST PATH I1913
J 0
(-3200 5700);
DISPLAY 0.978723 (-3200 5700);
PAINT WHITE (-3200 5700);
DISPLAY INVISIBLE (-3200 5700);
FORCEPROP 2 LAST BOM_COST MEM
J 2
(-3125 5700);
DISPLAY 0.744681 (-3125 5700);
PAINT WHITE (-3125 5700);
DISPLAY INVISIBLE (-3125 5700);
FORCEPROP 2 LAST CDS_LIB pure_quanta
J 2
(-3150 5550);
DISPLAY INVISIBLE (-3150 5550);
FORCEADD Q_RES..1
(-3150 5600);
FORCEPROP 1 LAST LOCATION R1203
J 0
(-3025 5600);
DISPLAY 0.489362 (-3025 5600);
PAINT SKYBLUE (-3025 5600);
FORCEPROP 0 LAST $SEC 1
J 0
(-3025 5650);
DISPLAY 0.680851 (-3025 5650);
PAINT MONO (-3025 5650);
DISPLAY INVISIBLE (-3025 5650);
FORCEPROP 0 LAST CDS_SEC 1
J 0
(-3025 5650);
DISPLAY 0.680851 (-3025 5650);
DISPLAY INVISIBLE (-3025 5650);
FORCEPROP 1 LASTPIN (-3250 5600) $PN 1
J 0
(-3238 5612);
DISPLAY 0.489362 (-3238 5612);
PAINT MONO (-3238 5612);
FORCEPROP 1 LASTPIN (-3050 5600) $PN 2
J 0
(-3088 5612);
DISPLAY 0.489362 (-3088 5612);
PAINT MONO (-3088 5612);
FORCEPROP 1 LAST VALUE 33
J 2
(-3275 5600);
DISPLAY 0.489362 (-3275 5600);
PAINT SKYBLUE (-3275 5600);
FORCEPROP 2 LAST CDS_LIB pure_quanta
J 0
(-3150 5600);
DISPLAY INVISIBLE (-3150 5600);
FORCEPROP 1 LAST PATH I1914
J 0
(-3200 5750);
DISPLAY 0.978723 (-3200 5750);
PAINT WHITE (-3200 5750);
DISPLAY INVISIBLE (-3200 5750);
FORCEPROP 2 LAST BOM_COST MEM
J 2
(-3125 5750);
DISPLAY 0.744681 (-3125 5750);
PAINT WHITE (-3125 5750);
DISPLAY INVISIBLE (-3125 5750);
FORCEPROP 1 LAST WATTAGE 1/16W
J 2
(-3225 5525);
DISPLAY 0.489362 (-3225 5525);
PAINT SKYBLUE (-3225 5525);
DISPLAY INVISIBLE (-3225 5525);
FORCEPROP 1 LAST MATERIAL CHIP
J 2
(-2975 5575);
DISPLAY 0.489362 (-2975 5575);
PAINT SKYBLUE (-2975 5575);
DISPLAY INVISIBLE (-2975 5575);
FORCEPROP 1 LAST TOLERANCE 5%
J 0
(-3275 5575);
DISPLAY 0.489362 (-3275 5575);
PAINT SKYBLUE (-3275 5575);
DISPLAY INVISIBLE (-3275 5575);
FORCEPROP 1 LAST PART_NUMBER CS03302JB29
J 2
(-3050 5650);
DISPLAY 0.489362 (-3050 5650);
PAINT SKYBLUE (-3050 5650);
DISPLAY INVISIBLE (-3050 5650);
FORCEPROP 1 LAST PACK_TYPE 0402LF
J 2
(-2975 5525);
DISPLAY 0.489362 (-2975 5525);
PAINT SKYBLUE (-2975 5525);
DISPLAY INVISIBLE (-2975 5525);
FORCEPROP 2 LAST ROOM RST_CPU0_PLD_TO_DIMM
J 2
(-3125 5700);
DISPLAY 0.744681 (-3125 5700);
PAINT RED (-3125 5700);
DISPLAY INVISIBLE (-3125 5700);
FORCEADD Q_RES..1
(-3150 4750);
FORCEPROP 1 LAST LOCATION R277
J 0
(-3025 4750);
DISPLAY 0.489362 (-3025 4750);
PAINT SKYBLUE (-3025 4750);
FORCEPROP 0 LAST $SEC 1
J 2
(-3025 4800);
DISPLAY 0.680851 (-3025 4800);
PAINT MONO (-3025 4800);
DISPLAY INVISIBLE (-3025 4800);
FORCEPROP 0 LAST CDS_SEC 1
J 2
(-3025 4800);
DISPLAY 1.021277 (-3025 4800);
DISPLAY INVISIBLE (-3025 4800);
FORCEPROP 1 LASTPIN (-3250 4750) $PN 1
J 0
(-3238 4762);
DISPLAY 0.489362 (-3238 4762);
PAINT MONO (-3238 4762);
FORCEPROP 1 LASTPIN (-3050 4750) $PN 2
J 0
(-3088 4762);
DISPLAY 0.489362 (-3088 4762);
PAINT MONO (-3088 4762);
FORCEPROP 1 LAST VALUE 33
J 2
(-3275 4750);
DISPLAY 0.489362 (-3275 4750);
PAINT SKYBLUE (-3275 4750);
FORCEPROP 2 LAST ROOM RST_CPU0_PLD_TO_DIMM
J 2
(-3125 4850);
DISPLAY 0.744681 (-3125 4850);
PAINT RED (-3125 4850);
DISPLAY INVISIBLE (-3125 4850);
FORCEPROP 1 LAST PACK_TYPE 0402LF
J 2
(-2975 4675);
DISPLAY 0.489362 (-2975 4675);
PAINT SKYBLUE (-2975 4675);
DISPLAY INVISIBLE (-2975 4675);
FORCEPROP 1 LAST PART_NUMBER CS03302JB29
J 2
(-3050 4800);
DISPLAY 0.489362 (-3050 4800);
PAINT SKYBLUE (-3050 4800);
DISPLAY INVISIBLE (-3050 4800);
FORCEPROP 1 LAST TOLERANCE 5%
J 0
(-3275 4725);
DISPLAY 0.489362 (-3275 4725);
PAINT SKYBLUE (-3275 4725);
DISPLAY INVISIBLE (-3275 4725);
FORCEPROP 1 LAST MATERIAL CHIP
J 2
(-2975 4725);
DISPLAY 0.489362 (-2975 4725);
PAINT SKYBLUE (-2975 4725);
DISPLAY INVISIBLE (-2975 4725);
FORCEPROP 1 LAST WATTAGE 1/16W
J 2
(-3225 4675);
DISPLAY 0.489362 (-3225 4675);
PAINT SKYBLUE (-3225 4675);
DISPLAY INVISIBLE (-3225 4675);
FORCEPROP 1 LAST PATH I1920
J 0
(-3200 4900);
DISPLAY 0.978723 (-3200 4900);
PAINT WHITE (-3200 4900);
DISPLAY INVISIBLE (-3200 4900);
FORCEPROP 2 LAST CDS_LIB pure_quanta
J 2
(-3150 4750);
DISPLAY INVISIBLE (-3150 4750);
FORCEPROP 2 LAST BOM_COST MEM
J 2
(-3125 4900);
DISPLAY 0.744681 (-3125 4900);
PAINT WHITE (-3125 4900);
DISPLAY INVISIBLE (-3125 4900);
FORCEADD Q_RES..1
(-6350 5900);
FORCEPROP 1 LAST LOCATION R254
J 0
(-6225 5900);
DISPLAY 0.489362 (-6225 5900);
PAINT SKYBLUE (-6225 5900);
FORCEPROP 0 LAST $SEC 1
J 2
(-6225 5950);
DISPLAY 0.680851 (-6225 5950);
PAINT MONO (-6225 5950);
DISPLAY INVISIBLE (-6225 5950);
FORCEPROP 0 LAST CDS_SEC 1
J 2
(-6225 5950);
DISPLAY 1.021277 (-6225 5950);
DISPLAY INVISIBLE (-6225 5950);
FORCEPROP 1 LASTPIN (-6450 5900) $PN 1
J 0
(-6438 5912);
DISPLAY 0.489362 (-6438 5912);
PAINT MONO (-6438 5912);
FORCEPROP 1 LASTPIN (-6250 5900) $PN 2
J 0
(-6288 5912);
DISPLAY 0.489362 (-6288 5912);
PAINT MONO (-6288 5912);
FORCEPROP 1 LAST VALUE 0
J 2
(-6475 5900);
DISPLAY 0.489362 (-6475 5900);
PAINT SKYBLUE (-6475 5900);
FORCEPROP 2 LAST ROOM RST_CPU0_PLD_TO_DIMM
J 2
(-6325 6000);
DISPLAY 0.744681 (-6325 6000);
PAINT RED (-6325 6000);
DISPLAY INVISIBLE (-6325 6000);
FORCEPROP 1 LAST PACK_TYPE 0402LF
J 2
(-6175 5825);
DISPLAY 0.489362 (-6175 5825);
PAINT SKYBLUE (-6175 5825);
DISPLAY INVISIBLE (-6175 5825);
FORCEPROP 1 LAST PART_NUMBER CS00002JB38
J 2
(-6250 5950);
DISPLAY 0.489362 (-6250 5950);
PAINT SKYBLUE (-6250 5950);
DISPLAY INVISIBLE (-6250 5950);
FORCEPROP 1 LAST TOLERANCE 5%
J 0
(-6475 5875);
DISPLAY 0.489362 (-6475 5875);
PAINT SKYBLUE (-6475 5875);
DISPLAY INVISIBLE (-6475 5875);
FORCEPROP 1 LAST MATERIAL CHIP
J 2
(-6175 5875);
DISPLAY 0.489362 (-6175 5875);
PAINT SKYBLUE (-6175 5875);
DISPLAY INVISIBLE (-6175 5875);
FORCEPROP 1 LAST WATTAGE 1/16W
J 2
(-6425 5825);
DISPLAY 0.489362 (-6425 5825);
PAINT SKYBLUE (-6425 5825);
DISPLAY INVISIBLE (-6425 5825);
FORCEPROP 1 LAST PATH I1921
J 0
(-6400 6050);
DISPLAY 0.978723 (-6400 6050);
PAINT WHITE (-6400 6050);
DISPLAY INVISIBLE (-6400 6050);
FORCEPROP 2 LAST BOM_COST MEM
J 2
(-6325 6050);
DISPLAY 0.744681 (-6325 6050);
PAINT WHITE (-6325 6050);
DISPLAY INVISIBLE (-6325 6050);
FORCEPROP 2 LAST CDS_LIB pure_quanta
J 2
(-6350 5900);
DISPLAY INVISIBLE (-6350 5900);
FORCEADD Q_RES..1
(-6350 5850);
FORCEPROP 1 LAST LOCATION R198
J 0
(-6225 5850);
DISPLAY 0.489362 (-6225 5850);
PAINT SKYBLUE (-6225 5850);
FORCEPROP 0 LAST $SEC 1
J 2
(-6225 5900);
DISPLAY 0.680851 (-6225 5900);
PAINT MONO (-6225 5900);
DISPLAY INVISIBLE (-6225 5900);
FORCEPROP 0 LAST CDS_SEC 1
J 2
(-6225 5900);
DISPLAY 1.021277 (-6225 5900);
DISPLAY INVISIBLE (-6225 5900);
FORCEPROP 1 LASTPIN (-6450 5850) $PN 1
J 0
(-6438 5862);
DISPLAY 0.489362 (-6438 5862);
PAINT MONO (-6438 5862);
FORCEPROP 1 LASTPIN (-6250 5850) $PN 2
J 0
(-6288 5862);
DISPLAY 0.489362 (-6288 5862);
PAINT MONO (-6288 5862);
FORCEPROP 1 LAST VALUE 0
J 2
(-6475 5850);
DISPLAY 0.489362 (-6475 5850);
PAINT SKYBLUE (-6475 5850);
FORCEPROP 2 LAST ROOM RST_CPU0_PLD_TO_DIMM
J 2
(-6325 5950);
DISPLAY 0.744681 (-6325 5950);
PAINT RED (-6325 5950);
DISPLAY INVISIBLE (-6325 5950);
FORCEPROP 1 LAST PACK_TYPE 0402LF
J 2
(-6175 5775);
DISPLAY 0.489362 (-6175 5775);
PAINT SKYBLUE (-6175 5775);
DISPLAY INVISIBLE (-6175 5775);
FORCEPROP 1 LAST PART_NUMBER CS00002JB38
J 2
(-6250 5900);
DISPLAY 0.489362 (-6250 5900);
PAINT SKYBLUE (-6250 5900);
DISPLAY INVISIBLE (-6250 5900);
FORCEPROP 1 LAST TOLERANCE 5%
J 0
(-6475 5825);
DISPLAY 0.489362 (-6475 5825);
PAINT SKYBLUE (-6475 5825);
DISPLAY INVISIBLE (-6475 5825);
FORCEPROP 1 LAST MATERIAL CHIP
J 2
(-6175 5825);
DISPLAY 0.489362 (-6175 5825);
PAINT SKYBLUE (-6175 5825);
DISPLAY INVISIBLE (-6175 5825);
FORCEPROP 1 LAST WATTAGE 1/16W
J 2
(-6425 5775);
DISPLAY 0.489362 (-6425 5775);
PAINT SKYBLUE (-6425 5775);
DISPLAY INVISIBLE (-6425 5775);
FORCEPROP 1 LAST PATH I1922
J 0
(-6400 6000);
DISPLAY 0.978723 (-6400 6000);
PAINT WHITE (-6400 6000);
DISPLAY INVISIBLE (-6400 6000);
FORCEPROP 2 LAST BOM_COST MEM
J 2
(-6325 6000);
DISPLAY 0.744681 (-6325 6000);
PAINT WHITE (-6325 6000);
DISPLAY INVISIBLE (-6325 6000);
FORCEPROP 2 LAST CDS_LIB pure_quanta
J 2
(-6350 5850);
DISPLAY INVISIBLE (-6350 5850);
FORCEADD Q_RES..1
(-6350 5500);
FORCEPROP 1 LAST LOCATION R197
J 0
(-6225 5500);
DISPLAY 0.489362 (-6225 5500);
PAINT SKYBLUE (-6225 5500);
FORCEPROP 0 LAST $SEC 1
J 2
(-6225 5550);
DISPLAY 0.680851 (-6225 5550);
PAINT MONO (-6225 5550);
DISPLAY INVISIBLE (-6225 5550);
FORCEPROP 0 LAST CDS_SEC 1
J 2
(-6225 5550);
DISPLAY 1.021277 (-6225 5550);
DISPLAY INVISIBLE (-6225 5550);
FORCEPROP 1 LASTPIN (-6450 5500) $PN 1
J 0
(-6438 5512);
DISPLAY 0.489362 (-6438 5512);
PAINT MONO (-6438 5512);
FORCEPROP 1 LASTPIN (-6250 5500) $PN 2
J 0
(-6288 5512);
DISPLAY 0.489362 (-6288 5512);
PAINT MONO (-6288 5512);
FORCEPROP 1 LAST VALUE 0
J 2
(-6475 5500);
DISPLAY 0.489362 (-6475 5500);
PAINT SKYBLUE (-6475 5500);
FORCEPROP 2 LAST ROOM RST_CPU0_PLD_TO_DIMM
J 2
(-6325 5600);
DISPLAY 0.744681 (-6325 5600);
PAINT RED (-6325 5600);
DISPLAY INVISIBLE (-6325 5600);
FORCEPROP 1 LAST PACK_TYPE 0402LF
J 2
(-6175 5425);
DISPLAY 0.489362 (-6175 5425);
PAINT SKYBLUE (-6175 5425);
DISPLAY INVISIBLE (-6175 5425);
FORCEPROP 1 LAST PART_NUMBER CS00002JB38
J 2
(-6250 5550);
DISPLAY 0.489362 (-6250 5550);
PAINT SKYBLUE (-6250 5550);
DISPLAY INVISIBLE (-6250 5550);
FORCEPROP 1 LAST TOLERANCE 5%
J 0
(-6475 5475);
DISPLAY 0.489362 (-6475 5475);
PAINT SKYBLUE (-6475 5475);
DISPLAY INVISIBLE (-6475 5475);
FORCEPROP 1 LAST MATERIAL CHIP
J 2
(-6175 5475);
DISPLAY 0.489362 (-6175 5475);
PAINT SKYBLUE (-6175 5475);
DISPLAY INVISIBLE (-6175 5475);
FORCEPROP 1 LAST WATTAGE 1/16W
J 2
(-6425 5425);
DISPLAY 0.489362 (-6425 5425);
PAINT SKYBLUE (-6425 5425);
DISPLAY INVISIBLE (-6425 5425);
FORCEPROP 1 LAST PATH I1923
J 0
(-6400 5650);
DISPLAY 0.978723 (-6400 5650);
PAINT WHITE (-6400 5650);
DISPLAY INVISIBLE (-6400 5650);
FORCEPROP 2 LAST BOM_COST MEM
J 2
(-6325 5650);
DISPLAY 0.744681 (-6325 5650);
PAINT WHITE (-6325 5650);
DISPLAY INVISIBLE (-6325 5650);
FORCEPROP 2 LAST CDS_LIB pure_quanta
J 2
(-6350 5500);
DISPLAY INVISIBLE (-6350 5500);
FORCEADD Q_RES..1
(-6350 5650);
FORCEPROP 1 LAST LOCATION R255
J 0
(-6225 5650);
DISPLAY 0.489362 (-6225 5650);
PAINT SKYBLUE (-6225 5650);
FORCEPROP 0 LAST $SEC 1
J 2
(-6225 5700);
DISPLAY 0.680851 (-6225 5700);
PAINT MONO (-6225 5700);
DISPLAY INVISIBLE (-6225 5700);
FORCEPROP 0 LAST CDS_SEC 1
J 2
(-6225 5700);
DISPLAY 1.021277 (-6225 5700);
DISPLAY INVISIBLE (-6225 5700);
FORCEPROP 1 LASTPIN (-6450 5650) $PN 1
J 0
(-6438 5662);
DISPLAY 0.489362 (-6438 5662);
PAINT MONO (-6438 5662);
FORCEPROP 1 LASTPIN (-6250 5650) $PN 2
J 0
(-6288 5662);
DISPLAY 0.489362 (-6288 5662);
PAINT MONO (-6288 5662);
FORCEPROP 1 LAST VALUE 0
J 2
(-6475 5650);
DISPLAY 0.489362 (-6475 5650);
PAINT SKYBLUE (-6475 5650);
FORCEPROP 2 LAST ROOM RST_CPU0_PLD_TO_DIMM
J 2
(-6325 5750);
DISPLAY 0.744681 (-6325 5750);
PAINT RED (-6325 5750);
DISPLAY INVISIBLE (-6325 5750);
FORCEPROP 1 LAST PACK_TYPE 0402LF
J 2
(-6175 5575);
DISPLAY 0.489362 (-6175 5575);
PAINT SKYBLUE (-6175 5575);
DISPLAY INVISIBLE (-6175 5575);
FORCEPROP 1 LAST PART_NUMBER CS00002JB38
J 2
(-6250 5700);
DISPLAY 0.489362 (-6250 5700);
PAINT SKYBLUE (-6250 5700);
DISPLAY INVISIBLE (-6250 5700);
FORCEPROP 1 LAST TOLERANCE 5%
J 0
(-6475 5625);
DISPLAY 0.489362 (-6475 5625);
PAINT SKYBLUE (-6475 5625);
DISPLAY INVISIBLE (-6475 5625);
FORCEPROP 1 LAST MATERIAL CHIP
J 2
(-6175 5625);
DISPLAY 0.489362 (-6175 5625);
PAINT SKYBLUE (-6175 5625);
DISPLAY INVISIBLE (-6175 5625);
FORCEPROP 1 LAST WATTAGE 1/16W
J 2
(-6425 5575);
DISPLAY 0.489362 (-6425 5575);
PAINT SKYBLUE (-6425 5575);
DISPLAY INVISIBLE (-6425 5575);
FORCEPROP 1 LAST PATH I1924
J 0
(-6400 5800);
DISPLAY 0.978723 (-6400 5800);
PAINT WHITE (-6400 5800);
DISPLAY INVISIBLE (-6400 5800);
FORCEPROP 2 LAST BOM_COST MEM
J 2
(-6325 5800);
DISPLAY 0.744681 (-6325 5800);
PAINT WHITE (-6325 5800);
DISPLAY INVISIBLE (-6325 5800);
FORCEPROP 2 LAST CDS_LIB pure_quanta
J 2
(-6350 5650);
DISPLAY INVISIBLE (-6350 5650);
FORCEADD Q_RES..1
(-6350 5400);
FORCEPROP 1 LAST LOCATION R273
J 0
(-6225 5400);
DISPLAY 0.489362 (-6225 5400);
PAINT SKYBLUE (-6225 5400);
FORCEPROP 0 LAST $SEC 1
J 2
(-6225 5450);
DISPLAY 0.680851 (-6225 5450);
PAINT MONO (-6225 5450);
DISPLAY INVISIBLE (-6225 5450);
FORCEPROP 0 LAST CDS_SEC 1
J 2
(-6225 5450);
DISPLAY 1.021277 (-6225 5450);
DISPLAY INVISIBLE (-6225 5450);
FORCEPROP 1 LASTPIN (-6450 5400) $PN 1
J 0
(-6438 5412);
DISPLAY 0.489362 (-6438 5412);
PAINT MONO (-6438 5412);
FORCEPROP 1 LASTPIN (-6250 5400) $PN 2
J 0
(-6288 5412);
DISPLAY 0.489362 (-6288 5412);
PAINT MONO (-6288 5412);
FORCEPROP 1 LAST VALUE 33
J 2
(-6475 5400);
DISPLAY 0.489362 (-6475 5400);
PAINT SKYBLUE (-6475 5400);
FORCEPROP 2 LAST ROOM RST_CPU0_PLD_TO_DIMM
J 2
(-6325 5500);
DISPLAY 0.744681 (-6325 5500);
PAINT RED (-6325 5500);
DISPLAY INVISIBLE (-6325 5500);
FORCEPROP 1 LAST PACK_TYPE 0402LF
J 2
(-6175 5325);
DISPLAY 0.489362 (-6175 5325);
PAINT SKYBLUE (-6175 5325);
DISPLAY INVISIBLE (-6175 5325);
FORCEPROP 1 LAST PART_NUMBER CS03302JB29
J 2
(-6250 5450);
DISPLAY 0.489362 (-6250 5450);
PAINT SKYBLUE (-6250 5450);
DISPLAY INVISIBLE (-6250 5450);
FORCEPROP 1 LAST TOLERANCE 5%
J 0
(-6475 5375);
DISPLAY 0.489362 (-6475 5375);
PAINT SKYBLUE (-6475 5375);
DISPLAY INVISIBLE (-6475 5375);
FORCEPROP 1 LAST MATERIAL CHIP
J 2
(-6175 5375);
DISPLAY 0.489362 (-6175 5375);
PAINT SKYBLUE (-6175 5375);
DISPLAY INVISIBLE (-6175 5375);
FORCEPROP 1 LAST WATTAGE 1/16W
J 2
(-6425 5325);
DISPLAY 0.489362 (-6425 5325);
PAINT SKYBLUE (-6425 5325);
DISPLAY INVISIBLE (-6425 5325);
FORCEPROP 1 LAST PATH I1925
J 0
(-6400 5550);
DISPLAY 0.978723 (-6400 5550);
PAINT WHITE (-6400 5550);
DISPLAY INVISIBLE (-6400 5550);
FORCEPROP 2 LAST CDS_LIB pure_quanta
J 2
(-6350 5400);
DISPLAY INVISIBLE (-6350 5400);
FORCEPROP 2 LAST BOM_COST MEM
J 2
(-6325 5550);
DISPLAY 0.744681 (-6325 5550);
PAINT WHITE (-6325 5550);
DISPLAY INVISIBLE (-6325 5550);
FORCEADD Q_RES..1
(-6350 5350);
FORCEPROP 1 LAST LOCATION R217
J 0
(-6225 5350);
DISPLAY 0.489362 (-6225 5350);
PAINT SKYBLUE (-6225 5350);
FORCEPROP 0 LAST $SEC 1
J 2
(-6225 5400);
DISPLAY 0.680851 (-6225 5400);
PAINT MONO (-6225 5400);
DISPLAY INVISIBLE (-6225 5400);
FORCEPROP 0 LAST CDS_SEC 1
J 2
(-6225 5400);
DISPLAY 1.021277 (-6225 5400);
DISPLAY INVISIBLE (-6225 5400);
FORCEPROP 1 LASTPIN (-6450 5350) $PN 1
J 0
(-6438 5362);
DISPLAY 0.489362 (-6438 5362);
PAINT MONO (-6438 5362);
FORCEPROP 1 LASTPIN (-6250 5350) $PN 2
J 0
(-6288 5362);
DISPLAY 0.489362 (-6288 5362);
PAINT MONO (-6288 5362);
FORCEPROP 1 LAST VALUE 33
J 2
(-6475 5350);
DISPLAY 0.489362 (-6475 5350);
PAINT SKYBLUE (-6475 5350);
FORCEPROP 2 LAST ROOM RST_CPU0_PLD_TO_DIMM
J 2
(-6325 5450);
DISPLAY 0.744681 (-6325 5450);
PAINT RED (-6325 5450);
DISPLAY INVISIBLE (-6325 5450);
FORCEPROP 1 LAST PACK_TYPE 0402LF
J 2
(-6175 5275);
DISPLAY 0.489362 (-6175 5275);
PAINT SKYBLUE (-6175 5275);
DISPLAY INVISIBLE (-6175 5275);
FORCEPROP 1 LAST PART_NUMBER CS03302JB29
J 2
(-6250 5400);
DISPLAY 0.489362 (-6250 5400);
PAINT SKYBLUE (-6250 5400);
DISPLAY INVISIBLE (-6250 5400);
FORCEPROP 1 LAST TOLERANCE 5%
J 0
(-6475 5325);
DISPLAY 0.489362 (-6475 5325);
PAINT SKYBLUE (-6475 5325);
DISPLAY INVISIBLE (-6475 5325);
FORCEPROP 1 LAST MATERIAL CHIP
J 2
(-6175 5325);
DISPLAY 0.489362 (-6175 5325);
PAINT SKYBLUE (-6175 5325);
DISPLAY INVISIBLE (-6175 5325);
FORCEPROP 1 LAST WATTAGE 1/16W
J 2
(-6425 5275);
DISPLAY 0.489362 (-6425 5275);
PAINT SKYBLUE (-6425 5275);
DISPLAY INVISIBLE (-6425 5275);
FORCEPROP 1 LAST PATH I1926
J 0
(-6400 5500);
DISPLAY 0.978723 (-6400 5500);
PAINT WHITE (-6400 5500);
DISPLAY INVISIBLE (-6400 5500);
FORCEPROP 2 LAST CDS_LIB pure_quanta
J 2
(-6350 5350);
DISPLAY INVISIBLE (-6350 5350);
FORCEPROP 2 LAST BOM_COST MEM
J 2
(-6325 5500);
DISPLAY 0.744681 (-6325 5500);
PAINT WHITE (-6325 5500);
DISPLAY INVISIBLE (-6325 5500);
FORCEADD Q_RES..1
(-6350 5250);
FORCEPROP 1 LAST LOCATION R216
J 0
(-6225 5250);
DISPLAY 0.489362 (-6225 5250);
PAINT SKYBLUE (-6225 5250);
FORCEPROP 0 LAST $SEC 1
J 2
(-6225 5300);
DISPLAY 0.680851 (-6225 5300);
PAINT MONO (-6225 5300);
DISPLAY INVISIBLE (-6225 5300);
FORCEPROP 0 LAST CDS_SEC 1
J 2
(-6225 5300);
DISPLAY 1.021277 (-6225 5300);
DISPLAY INVISIBLE (-6225 5300);
FORCEPROP 1 LASTPIN (-6450 5250) $PN 1
J 0
(-6438 5262);
DISPLAY 0.489362 (-6438 5262);
PAINT MONO (-6438 5262);
FORCEPROP 1 LASTPIN (-6250 5250) $PN 2
J 0
(-6288 5262);
DISPLAY 0.489362 (-6288 5262);
PAINT MONO (-6288 5262);
FORCEPROP 1 LAST VALUE 33
J 2
(-6475 5250);
DISPLAY 0.489362 (-6475 5250);
PAINT SKYBLUE (-6475 5250);
FORCEPROP 2 LAST ROOM RST_CPU0_PLD_TO_DIMM
J 2
(-6325 5350);
DISPLAY 0.744681 (-6325 5350);
PAINT RED (-6325 5350);
DISPLAY INVISIBLE (-6325 5350);
FORCEPROP 1 LAST PACK_TYPE 0402LF
J 2
(-6175 5175);
DISPLAY 0.489362 (-6175 5175);
PAINT SKYBLUE (-6175 5175);
DISPLAY INVISIBLE (-6175 5175);
FORCEPROP 1 LAST PART_NUMBER CS03302JB29
J 2
(-6250 5300);
DISPLAY 0.489362 (-6250 5300);
PAINT SKYBLUE (-6250 5300);
DISPLAY INVISIBLE (-6250 5300);
FORCEPROP 1 LAST TOLERANCE 5%
J 0
(-6475 5225);
DISPLAY 0.489362 (-6475 5225);
PAINT SKYBLUE (-6475 5225);
DISPLAY INVISIBLE (-6475 5225);
FORCEPROP 1 LAST MATERIAL CHIP
J 2
(-6175 5225);
DISPLAY 0.489362 (-6175 5225);
PAINT SKYBLUE (-6175 5225);
DISPLAY INVISIBLE (-6175 5225);
FORCEPROP 1 LAST WATTAGE 1/16W
J 2
(-6425 5175);
DISPLAY 0.489362 (-6425 5175);
PAINT SKYBLUE (-6425 5175);
DISPLAY INVISIBLE (-6425 5175);
FORCEPROP 1 LAST PATH I1927
J 0
(-6400 5400);
DISPLAY 0.978723 (-6400 5400);
PAINT WHITE (-6400 5400);
DISPLAY INVISIBLE (-6400 5400);
FORCEPROP 2 LAST CDS_LIB pure_quanta
J 2
(-6350 5250);
DISPLAY INVISIBLE (-6350 5250);
FORCEPROP 2 LAST BOM_COST MEM
J 2
(-6325 5400);
DISPLAY 0.744681 (-6325 5400);
PAINT WHITE (-6325 5400);
DISPLAY INVISIBLE (-6325 5400);
FORCEADD Q_RES..1
(-6350 5150);
FORCEPROP 1 LAST LOCATION R253
J 0
(-6225 5150);
DISPLAY 0.489362 (-6225 5150);
PAINT SKYBLUE (-6225 5150);
FORCEPROP 0 LAST $SEC 1
J 2
(-6225 5200);
DISPLAY 0.680851 (-6225 5200);
PAINT MONO (-6225 5200);
DISPLAY INVISIBLE (-6225 5200);
FORCEPROP 0 LAST CDS_SEC 1
J 2
(-6225 5200);
DISPLAY 1.021277 (-6225 5200);
DISPLAY INVISIBLE (-6225 5200);
FORCEPROP 1 LASTPIN (-6450 5150) $PN 1
J 0
(-6438 5162);
DISPLAY 0.489362 (-6438 5162);
PAINT MONO (-6438 5162);
FORCEPROP 1 LASTPIN (-6250 5150) $PN 2
J 0
(-6288 5162);
DISPLAY 0.489362 (-6288 5162);
PAINT MONO (-6288 5162);
FORCEPROP 1 LAST VALUE 0
J 2
(-6475 5150);
DISPLAY 0.489362 (-6475 5150);
PAINT SKYBLUE (-6475 5150);
FORCEPROP 2 LAST ROOM RST_CPU0_PLD_TO_DIMM
J 2
(-6325 5250);
DISPLAY 0.744681 (-6325 5250);
PAINT RED (-6325 5250);
DISPLAY INVISIBLE (-6325 5250);
FORCEPROP 1 LAST PACK_TYPE 0402LF
J 2
(-6175 5075);
DISPLAY 0.489362 (-6175 5075);
PAINT SKYBLUE (-6175 5075);
DISPLAY INVISIBLE (-6175 5075);
FORCEPROP 1 LAST PART_NUMBER CS00002JB38
J 2
(-6250 5200);
DISPLAY 0.489362 (-6250 5200);
PAINT SKYBLUE (-6250 5200);
DISPLAY INVISIBLE (-6250 5200);
FORCEPROP 1 LAST TOLERANCE 5%
J 0
(-6475 5125);
DISPLAY 0.489362 (-6475 5125);
PAINT SKYBLUE (-6475 5125);
DISPLAY INVISIBLE (-6475 5125);
FORCEPROP 1 LAST MATERIAL CHIP
J 2
(-6175 5125);
DISPLAY 0.489362 (-6175 5125);
PAINT SKYBLUE (-6175 5125);
DISPLAY INVISIBLE (-6175 5125);
FORCEPROP 1 LAST WATTAGE 1/16W
J 2
(-6425 5075);
DISPLAY 0.489362 (-6425 5075);
PAINT SKYBLUE (-6425 5075);
DISPLAY INVISIBLE (-6425 5075);
FORCEPROP 1 LAST PATH I1928
J 0
(-6400 5300);
DISPLAY 0.978723 (-6400 5300);
PAINT WHITE (-6400 5300);
DISPLAY INVISIBLE (-6400 5300);
FORCEPROP 2 LAST CDS_LIB pure_quanta
J 2
(-6350 5150);
DISPLAY INVISIBLE (-6350 5150);
FORCEPROP 2 LAST BOM_COST MEM
J 2
(-6325 5300);
DISPLAY 0.744681 (-6325 5300);
PAINT WHITE (-6325 5300);
DISPLAY INVISIBLE (-6325 5300);
FORCEADD Q_RES..1
(-6350 5200);
FORCEPROP 1 LAST LOCATION R272
J 0
(-6225 5200);
DISPLAY 0.489362 (-6225 5200);
PAINT SKYBLUE (-6225 5200);
FORCEPROP 0 LAST $SEC 1
J 2
(-6225 5250);
DISPLAY 0.680851 (-6225 5250);
PAINT MONO (-6225 5250);
DISPLAY INVISIBLE (-6225 5250);
FORCEPROP 0 LAST CDS_SEC 1
J 2
(-6225 5250);
DISPLAY 1.021277 (-6225 5250);
DISPLAY INVISIBLE (-6225 5250);
FORCEPROP 1 LASTPIN (-6450 5200) $PN 1
J 0
(-6438 5212);
DISPLAY 0.489362 (-6438 5212);
PAINT MONO (-6438 5212);
FORCEPROP 1 LASTPIN (-6250 5200) $PN 2
J 0
(-6288 5212);
DISPLAY 0.489362 (-6288 5212);
PAINT MONO (-6288 5212);
FORCEPROP 1 LAST MATERIAL EMPTY
J 2
(-6525 5200);
DISPLAY 0.489362 (-6525 5200);
PAINT RED (-6525 5200);
FORCEPROP 1 LAST VALUE 0
J 2
(-6475 5200);
DISPLAY 0.489362 (-6475 5200);
PAINT SKYBLUE (-6475 5200);
FORCEPROP 2 LAST ROOM RST_CPU0_PLD_TO_DIMM
J 2
(-6325 5300);
DISPLAY 0.744681 (-6325 5300);
PAINT RED (-6325 5300);
DISPLAY INVISIBLE (-6325 5300);
FORCEPROP 1 LAST PACK_TYPE 0402LF
J 2
(-6175 5125);
DISPLAY 0.489362 (-6175 5125);
PAINT SKYBLUE (-6175 5125);
DISPLAY INVISIBLE (-6175 5125);
FORCEPROP 1 LAST PART_NUMBER CS00002JB38
J 2
(-6250 5250);
DISPLAY 0.489362 (-6250 5250);
PAINT SKYBLUE (-6250 5250);
DISPLAY INVISIBLE (-6250 5250);
FORCEPROP 1 LAST TOLERANCE 5%
J 0
(-6475 5175);
DISPLAY 0.489362 (-6475 5175);
PAINT SKYBLUE (-6475 5175);
DISPLAY INVISIBLE (-6475 5175);
FORCEPROP 1 LAST WATTAGE 1/16W
J 2
(-6425 5125);
DISPLAY 0.489362 (-6425 5125);
PAINT SKYBLUE (-6425 5125);
DISPLAY INVISIBLE (-6425 5125);
FORCEPROP 1 LAST PATH I1929
J 0
(-6400 5350);
DISPLAY 0.978723 (-6400 5350);
PAINT WHITE (-6400 5350);
DISPLAY INVISIBLE (-6400 5350);
FORCEPROP 2 LAST BOM_COST MEM
J 2
(-6325 5350);
DISPLAY 0.744681 (-6325 5350);
PAINT WHITE (-6325 5350);
DISPLAY INVISIBLE (-6325 5350);
FORCEPROP 2 LAST CDS_LIB pure_quanta
J 2
(-6350 5200);
DISPLAY INVISIBLE (-6350 5200);
FORCEADD Q_RES..1
(-6350 5000);
FORCEPROP 1 LAST LOCATION R241
J 0
(-6225 5000);
DISPLAY 0.489362 (-6225 5000);
PAINT SKYBLUE (-6225 5000);
FORCEPROP 0 LAST $SEC 1
J 2
(-6225 5050);
DISPLAY 0.680851 (-6225 5050);
PAINT MONO (-6225 5050);
DISPLAY INVISIBLE (-6225 5050);
FORCEPROP 0 LAST CDS_SEC 1
J 2
(-6225 5050);
DISPLAY 1.021277 (-6225 5050);
DISPLAY INVISIBLE (-6225 5050);
FORCEPROP 1 LASTPIN (-6450 5000) $PN 1
J 0
(-6438 5012);
DISPLAY 0.489362 (-6438 5012);
PAINT MONO (-6438 5012);
FORCEPROP 1 LASTPIN (-6250 5000) $PN 2
J 0
(-6288 5012);
DISPLAY 0.489362 (-6288 5012);
PAINT MONO (-6288 5012);
FORCEPROP 1 LAST VALUE 0
J 2
(-6475 5000);
DISPLAY 0.489362 (-6475 5000);
PAINT SKYBLUE (-6475 5000);
FORCEPROP 2 LAST ROOM RST_CPU0_PLD_TO_DIMM
J 2
(-6325 5100);
DISPLAY 0.744681 (-6325 5100);
PAINT RED (-6325 5100);
DISPLAY INVISIBLE (-6325 5100);
FORCEPROP 1 LAST PACK_TYPE 0402LF
J 2
(-6175 4925);
DISPLAY 0.489362 (-6175 4925);
PAINT SKYBLUE (-6175 4925);
DISPLAY INVISIBLE (-6175 4925);
FORCEPROP 1 LAST PART_NUMBER CS00002JB38
J 2
(-6250 5050);
DISPLAY 0.489362 (-6250 5050);
PAINT SKYBLUE (-6250 5050);
DISPLAY INVISIBLE (-6250 5050);
FORCEPROP 1 LAST TOLERANCE 5%
J 0
(-6475 4975);
DISPLAY 0.489362 (-6475 4975);
PAINT SKYBLUE (-6475 4975);
DISPLAY INVISIBLE (-6475 4975);
FORCEPROP 1 LAST MATERIAL CHIP
J 2
(-6175 4975);
DISPLAY 0.489362 (-6175 4975);
PAINT SKYBLUE (-6175 4975);
DISPLAY INVISIBLE (-6175 4975);
FORCEPROP 1 LAST WATTAGE 1/16W
J 2
(-6425 4925);
DISPLAY 0.489362 (-6425 4925);
PAINT SKYBLUE (-6425 4925);
DISPLAY INVISIBLE (-6425 4925);
FORCEPROP 1 LAST PATH I1930
J 0
(-6400 5150);
DISPLAY 0.978723 (-6400 5150);
PAINT WHITE (-6400 5150);
DISPLAY INVISIBLE (-6400 5150);
FORCEPROP 2 LAST CDS_LIB pure_quanta
J 2
(-6350 5000);
DISPLAY INVISIBLE (-6350 5000);
FORCEPROP 2 LAST BOM_COST MEM
J 2
(-6325 5150);
DISPLAY 0.744681 (-6325 5150);
PAINT WHITE (-6325 5150);
DISPLAY INVISIBLE (-6325 5150);
FORCEADD Q_RES..1
(-6350 4950);
FORCEPROP 1 LAST LOCATION R57
J 0
(-6225 4950);
DISPLAY 0.489362 (-6225 4950);
PAINT SKYBLUE (-6225 4950);
FORCEPROP 0 LAST $SEC 1
J 0
(-6200 5000);
DISPLAY 0.680851 (-6200 5000);
PAINT MONO (-6200 5000);
DISPLAY INVISIBLE (-6200 5000);
FORCEPROP 0 LAST CDS_SEC 1
J 0
(-6200 5000);
DISPLAY 1.021277 (-6200 5000);
DISPLAY INVISIBLE (-6200 5000);
FORCEPROP 1 LASTPIN (-6450 4950) $PN 1
J 0
(-6438 4962);
DISPLAY 0.489362 (-6438 4962);
PAINT MONO (-6438 4962);
FORCEPROP 1 LASTPIN (-6250 4950) $PN 2
J 0
(-6288 4962);
DISPLAY 0.489362 (-6288 4962);
PAINT MONO (-6288 4962);
FORCEPROP 1 LAST VALUE 0
J 2
(-6475 4950);
DISPLAY 0.489362 (-6475 4950);
PAINT SKYBLUE (-6475 4950);
FORCEPROP 2 LAST ROOM RST_CPU0_PLD_TO_DIMM
J 2
(-6325 5050);
DISPLAY 0.744681 (-6325 5050);
PAINT RED (-6325 5050);
DISPLAY INVISIBLE (-6325 5050);
FORCEPROP 1 LAST PACK_TYPE 0402LF
J 2
(-6175 4875);
DISPLAY 0.489362 (-6175 4875);
PAINT SKYBLUE (-6175 4875);
DISPLAY INVISIBLE (-6175 4875);
FORCEPROP 1 LAST PART_NUMBER CS00002JB38
J 2
(-6250 5000);
DISPLAY 0.489362 (-6250 5000);
PAINT SKYBLUE (-6250 5000);
DISPLAY INVISIBLE (-6250 5000);
FORCEPROP 1 LAST TOLERANCE 5%
J 0
(-6475 4925);
DISPLAY 0.489362 (-6475 4925);
PAINT SKYBLUE (-6475 4925);
DISPLAY INVISIBLE (-6475 4925);
FORCEPROP 1 LAST MATERIAL CHIP
J 2
(-6175 4925);
DISPLAY 0.489362 (-6175 4925);
PAINT SKYBLUE (-6175 4925);
DISPLAY INVISIBLE (-6175 4925);
FORCEPROP 1 LAST WATTAGE 1/16W
J 2
(-6425 4875);
DISPLAY 0.489362 (-6425 4875);
PAINT SKYBLUE (-6425 4875);
DISPLAY INVISIBLE (-6425 4875);
FORCEPROP 1 LAST PATH I1931
J 0
(-6400 5100);
DISPLAY 0.978723 (-6400 5100);
PAINT WHITE (-6400 5100);
DISPLAY INVISIBLE (-6400 5100);
FORCEPROP 2 LAST BOM_COST MEM
J 2
(-6325 5100);
DISPLAY 0.744681 (-6325 5100);
PAINT WHITE (-6325 5100);
DISPLAY INVISIBLE (-6325 5100);
FORCEPROP 2 LAST CDS_LIB pure_quanta
J 0
(-6350 4950);
DISPLAY INVISIBLE (-6350 4950);
FORCEADD Q_RES..1
(-6350 4900);
FORCEPROP 1 LAST LOCATION R463
J 0
(-6225 4900);
DISPLAY 0.489362 (-6225 4900);
PAINT SKYBLUE (-6225 4900);
FORCEPROP 0 LAST $SEC 1
J 0
(-6225 4925);
DISPLAY 0.680851 (-6225 4925);
PAINT MONO (-6225 4925);
DISPLAY INVISIBLE (-6225 4925);
FORCEPROP 0 LAST CDS_SEC 1
J 0
(-6225 4925);
DISPLAY 1.021277 (-6225 4925);
DISPLAY INVISIBLE (-6225 4925);
FORCEPROP 1 LASTPIN (-6450 4900) $PN 1
J 0
(-6438 4912);
DISPLAY 0.489362 (-6438 4912);
PAINT MONO (-6438 4912);
FORCEPROP 1 LASTPIN (-6250 4900) $PN 2
J 0
(-6288 4912);
DISPLAY 0.489362 (-6288 4912);
PAINT MONO (-6288 4912);
FORCEPROP 1 LAST VALUE 33
J 2
(-6450 4900);
DISPLAY 0.489362 (-6450 4900);
PAINT SKYBLUE (-6450 4900);
FORCEPROP 2 LAST CDS_LIB pure_quanta
J 0
(-6350 4900);
DISPLAY INVISIBLE (-6350 4900);
FORCEPROP 1 LAST PATH I1932
J 0
(-6400 5050);
DISPLAY 0.978723 (-6400 5050);
PAINT WHITE (-6400 5050);
DISPLAY INVISIBLE (-6400 5050);
FORCEPROP 1 LAST WATTAGE 1/16W
J 2
(-5950 4825);
DISPLAY 0.489362 (-5950 4825);
PAINT SKYBLUE (-5950 4825);
DISPLAY INVISIBLE (-5950 4825);
FORCEPROP 1 LAST MATERIAL CHIP
J 0
(-5925 4825);
DISPLAY 0.489362 (-5925 4825);
PAINT SKYBLUE (-5925 4825);
DISPLAY INVISIBLE (-5925 4825);
FORCEPROP 1 LAST TOLERANCE 5%
J 0
(-6375 4825);
DISPLAY 0.489362 (-6375 4825);
PAINT SKYBLUE (-6375 4825);
DISPLAY INVISIBLE (-6375 4825);
FORCEPROP 1 LAST PART_NUMBER CS03302JB29
J 0
(-6325 4950);
DISPLAY 0.489362 (-6325 4950);
PAINT SKYBLUE (-6325 4950);
DISPLAY INVISIBLE (-6325 4950);
FORCEPROP 1 LAST PACK_TYPE 0402LF
J 0
(-6300 4825);
DISPLAY 0.489362 (-6300 4825);
PAINT SKYBLUE (-6300 4825);
DISPLAY INVISIBLE (-6300 4825);
FORCEADD Q_RES..1
(-6350 4750);
FORCEPROP 1 LAST LOCATION R196
J 0
(-6225 4750);
DISPLAY 0.489362 (-6225 4750);
PAINT SKYBLUE (-6225 4750);
FORCEPROP 0 LAST $SEC 1
J 2
(-6225 4800);
DISPLAY 0.680851 (-6225 4800);
PAINT MONO (-6225 4800);
DISPLAY INVISIBLE (-6225 4800);
FORCEPROP 0 LAST CDS_SEC 1
J 2
(-6225 4800);
DISPLAY 1.021277 (-6225 4800);
DISPLAY INVISIBLE (-6225 4800);
FORCEPROP 1 LASTPIN (-6450 4750) $PN 1
J 0
(-6438 4762);
DISPLAY 0.489362 (-6438 4762);
PAINT MONO (-6438 4762);
FORCEPROP 1 LASTPIN (-6250 4750) $PN 2
J 0
(-6288 4762);
DISPLAY 0.489362 (-6288 4762);
PAINT MONO (-6288 4762);
FORCEPROP 1 LAST VALUE 0
J 2
(-6475 4750);
DISPLAY 0.489362 (-6475 4750);
PAINT SKYBLUE (-6475 4750);
FORCEPROP 2 LAST ROOM RST_CPU0_PLD_TO_DIMM
J 2
(-6325 4850);
DISPLAY 0.744681 (-6325 4850);
PAINT RED (-6325 4850);
DISPLAY INVISIBLE (-6325 4850);
FORCEPROP 1 LAST PACK_TYPE 0402LF
J 2
(-6175 4675);
DISPLAY 0.489362 (-6175 4675);
PAINT SKYBLUE (-6175 4675);
DISPLAY INVISIBLE (-6175 4675);
FORCEPROP 1 LAST PART_NUMBER CS00002JB38
J 2
(-6250 4800);
DISPLAY 0.489362 (-6250 4800);
PAINT SKYBLUE (-6250 4800);
DISPLAY INVISIBLE (-6250 4800);
FORCEPROP 1 LAST TOLERANCE 5%
J 0
(-6475 4725);
DISPLAY 0.489362 (-6475 4725);
PAINT SKYBLUE (-6475 4725);
DISPLAY INVISIBLE (-6475 4725);
FORCEPROP 1 LAST MATERIAL CHIP
J 2
(-6175 4725);
DISPLAY 0.489362 (-6175 4725);
PAINT SKYBLUE (-6175 4725);
DISPLAY INVISIBLE (-6175 4725);
FORCEPROP 1 LAST WATTAGE 1/16W
J 2
(-6425 4675);
DISPLAY 0.489362 (-6425 4675);
PAINT SKYBLUE (-6425 4675);
DISPLAY INVISIBLE (-6425 4675);
FORCEPROP 1 LAST PATH I1934
J 0
(-6400 4900);
DISPLAY 0.978723 (-6400 4900);
PAINT WHITE (-6400 4900);
DISPLAY INVISIBLE (-6400 4900);
FORCEPROP 2 LAST BOM_COST MEM
J 2
(-6325 4900);
DISPLAY 0.744681 (-6325 4900);
PAINT WHITE (-6325 4900);
DISPLAY INVISIBLE (-6325 4900);
FORCEPROP 2 LAST CDS_LIB pure_quanta
J 2
(-6350 4750);
DISPLAY INVISIBLE (-6350 4750);
FORCEADD Q_RES..1
(-6350 4800);
FORCEPROP 1 LAST LOCATION R242
J 0
(-6225 4800);
DISPLAY 0.489362 (-6225 4800);
PAINT SKYBLUE (-6225 4800);
FORCEPROP 0 LAST $SEC 1
J 2
(-6225 4850);
DISPLAY 0.680851 (-6225 4850);
PAINT MONO (-6225 4850);
DISPLAY INVISIBLE (-6225 4850);
FORCEPROP 0 LAST CDS_SEC 1
J 2
(-6225 4850);
DISPLAY 1.021277 (-6225 4850);
DISPLAY INVISIBLE (-6225 4850);
FORCEPROP 1 LASTPIN (-6450 4800) $PN 1
J 0
(-6438 4812);
DISPLAY 0.489362 (-6438 4812);
PAINT MONO (-6438 4812);
FORCEPROP 1 LASTPIN (-6250 4800) $PN 2
J 0
(-6288 4812);
DISPLAY 0.489362 (-6288 4812);
PAINT MONO (-6288 4812);
FORCEPROP 1 LAST VALUE 0
J 2
(-6475 4800);
DISPLAY 0.489362 (-6475 4800);
PAINT SKYBLUE (-6475 4800);
FORCEPROP 2 LAST ROOM RST_CPU0_PLD_TO_DIMM
J 2
(-6325 4900);
DISPLAY 0.744681 (-6325 4900);
PAINT RED (-6325 4900);
DISPLAY INVISIBLE (-6325 4900);
FORCEPROP 1 LAST PACK_TYPE 0402LF
J 2
(-6175 4725);
DISPLAY 0.489362 (-6175 4725);
PAINT SKYBLUE (-6175 4725);
DISPLAY INVISIBLE (-6175 4725);
FORCEPROP 1 LAST PART_NUMBER CS00002JB38
J 2
(-6250 4850);
DISPLAY 0.489362 (-6250 4850);
PAINT SKYBLUE (-6250 4850);
DISPLAY INVISIBLE (-6250 4850);
FORCEPROP 1 LAST TOLERANCE 5%
J 0
(-6475 4775);
DISPLAY 0.489362 (-6475 4775);
PAINT SKYBLUE (-6475 4775);
DISPLAY INVISIBLE (-6475 4775);
FORCEPROP 1 LAST MATERIAL CHIP
J 2
(-6175 4775);
DISPLAY 0.489362 (-6175 4775);
PAINT SKYBLUE (-6175 4775);
DISPLAY INVISIBLE (-6175 4775);
FORCEPROP 1 LAST WATTAGE 1/16W
J 2
(-6425 4725);
DISPLAY 0.489362 (-6425 4725);
PAINT SKYBLUE (-6425 4725);
DISPLAY INVISIBLE (-6425 4725);
FORCEPROP 1 LAST PATH I1935
J 0
(-6400 4950);
DISPLAY 0.978723 (-6400 4950);
PAINT WHITE (-6400 4950);
DISPLAY INVISIBLE (-6400 4950);
FORCEPROP 2 LAST CDS_LIB pure_quanta
J 2
(-6350 4800);
DISPLAY INVISIBLE (-6350 4800);
FORCEPROP 2 LAST BOM_COST MEM
J 2
(-6325 4950);
DISPLAY 0.744681 (-6325 4950);
PAINT WHITE (-6325 4950);
DISPLAY INVISIBLE (-6325 4950);
FORCEADD OFFPAGE..2
(-2225 4650);
FORCEPROP 2 LAST $XR1 29 
J 0
(-1946 4650);
DISPLAY 0.638298 (-1946 4650);
PAINT MONO (-1946 4650);
FORCEPROP 2 LAST $XR0 82 
J 0
(-2036 4650);
DISPLAY 0.638298 (-2036 4650);
PAINT MONO (-2036 4650);
FORCEPROP 1 LAST COMMENT_BODY TRUE
J 0
(-2270 4555);
DISPLAY 0.872340 (-2270 4555);
PAINT GREEN (-2270 4555);
DISPLAY INVISIBLE (-2270 4555);
FORCEPROP 1 LAST OFFPAGE TRUE
J 0
(-1900 4525);
DISPLAY 0.872340 (-1900 4525);
PAINT GREEN (-1900 4525);
DISPLAY INVISIBLE (-1900 4525);
FORCEPROP 2 LAST CDS_LIB standard
J 0
(-2225 4650);
DISPLAY INVISIBLE (-2225 4650);
FORCEPROP 2 LAST PATH I1936
J 0
(-1925 4700);
DISPLAY 0.680851 (-1925 4700);
DISPLAY INVISIBLE (-1925 4700);
FORCEADD OFFPAGE..1
R 2
(-2225 4700);
FORCEPROP 2 LAST $XR0 140 
J 0
(-2039 4700);
DISPLAY 0.638298 (-2039 4700);
PAINT MONO (-2039 4700);
FORCEPROP 1 LAST COMMENT_BODY TRUE
J 2
(-2350 4600);
DISPLAY 0.872340 (-2350 4600);
PAINT GREEN (-2350 4600);
DISPLAY INVISIBLE (-2350 4600);
FORCEPROP 1 LAST OFFPAGE TRUE
J 2
(-2550 4575);
DISPLAY 0.872340 (-2550 4575);
PAINT GREEN (-2550 4575);
DISPLAY INVISIBLE (-2550 4575);
FORCEPROP 2 LAST CDS_LIB standard
J 0
(-2225 4700);
DISPLAY INVISIBLE (-2225 4700);
FORCEPROP 2 LAST PATH I1937
J 0
(-2025 4750);
DISPLAY 0.680851 (-2025 4750);
DISPLAY INVISIBLE (-2025 4750);
FORCEADD OFFPAGE..1
R 2
(-2225 4550);
FORCEPROP 2 LAST $XR0 28 
J 0
(-2039 4550);
DISPLAY 0.638298 (-2039 4550);
PAINT MONO (-2039 4550);
FORCEPROP 1 LAST COMMENT_BODY TRUE
J 2
(-2350 4450);
DISPLAY 0.872340 (-2350 4450);
PAINT GREEN (-2350 4450);
DISPLAY INVISIBLE (-2350 4450);
FORCEPROP 1 LAST OFFPAGE TRUE
J 2
(-2550 4425);
DISPLAY 0.872340 (-2550 4425);
PAINT GREEN (-2550 4425);
DISPLAY INVISIBLE (-2550 4425);
FORCEPROP 2 LAST CDS_LIB standard
J 0
(-2225 4550);
DISPLAY INVISIBLE (-2225 4550);
FORCEPROP 2 LAST PATH I1938
J 0
(-2025 4600);
DISPLAY 0.680851 (-2025 4600);
DISPLAY INVISIBLE (-2025 4600);
FORCEADD OFFPAGE..2
(-2225 4500);
FORCEPROP 2 LAST $XR0 151 
J 0
(-2036 4500);
DISPLAY 0.638298 (-2036 4500);
PAINT MONO (-2036 4500);
FORCEPROP 1 LAST COMMENT_BODY TRUE
J 0
(-2270 4405);
DISPLAY 0.872340 (-2270 4405);
PAINT GREEN (-2270 4405);
DISPLAY INVISIBLE (-2270 4405);
FORCEPROP 1 LAST OFFPAGE TRUE
J 0
(-1900 4375);
DISPLAY 0.872340 (-1900 4375);
PAINT GREEN (-1900 4375);
DISPLAY INVISIBLE (-1900 4375);
FORCEPROP 2 LAST CDS_LIB standard
J 2
(-2225 4500);
DISPLAY INVISIBLE (-2225 4500);
FORCEPROP 2 LAST PATH I1939
J 0
(-2025 4550);
DISPLAY 0.680851 (-2025 4550);
DISPLAY INVISIBLE (-2025 4550);
FORCEADD OFFPAGE..2
(-2225 4300);
FORCEPROP 2 LAST $XR0 143 
J 0
(-2036 4300);
DISPLAY 0.638298 (-2036 4300);
PAINT MONO (-2036 4300);
FORCEPROP 1 LAST COMMENT_BODY TRUE
J 0
(-2270 4205);
DISPLAY 0.872340 (-2270 4205);
PAINT GREEN (-2270 4205);
DISPLAY INVISIBLE (-2270 4205);
FORCEPROP 1 LAST OFFPAGE TRUE
J 0
(-1900 4175);
DISPLAY 0.872340 (-1900 4175);
PAINT GREEN (-1900 4175);
DISPLAY INVISIBLE (-1900 4175);
FORCEPROP 2 LAST CDS_LIB standard
J 0
(-2225 4300);
DISPLAY INVISIBLE (-2225 4300);
FORCEPROP 2 LAST PATH I1940
J 0
(-2025 4350);
DISPLAY 0.680851 (-2025 4350);
DISPLAY INVISIBLE (-2025 4350);
FORCEADD OFFPAGE..2
(-2225 4450);
FORCEPROP 2 LAST $XR0 150 
J 0
(-2036 4450);
DISPLAY 0.638298 (-2036 4450);
PAINT MONO (-2036 4450);
FORCEPROP 1 LAST COMMENT_BODY TRUE
J 0
(-2270 4355);
DISPLAY 0.872340 (-2270 4355);
PAINT GREEN (-2270 4355);
DISPLAY INVISIBLE (-2270 4355);
FORCEPROP 1 LAST OFFPAGE TRUE
J 0
(-1900 4325);
DISPLAY 0.872340 (-1900 4325);
PAINT GREEN (-1900 4325);
DISPLAY INVISIBLE (-1900 4325);
FORCEPROP 2 LAST CDS_LIB standard
J 0
(-2225 4450);
DISPLAY INVISIBLE (-2225 4450);
FORCEPROP 2 LAST PATH I1941
J 0
(-2025 4500);
DISPLAY 0.680851 (-2025 4500);
DISPLAY INVISIBLE (-2025 4500);
FORCEADD OFFPAGE..2
(-2225 4400);
FORCEPROP 2 LAST $XR0 83 
J 0
(-2036 4400);
DISPLAY 0.638298 (-2036 4400);
PAINT MONO (-2036 4400);
FORCEPROP 1 LAST COMMENT_BODY TRUE
J 0
(-2270 4305);
DISPLAY 0.872340 (-2270 4305);
PAINT GREEN (-2270 4305);
DISPLAY INVISIBLE (-2270 4305);
FORCEPROP 1 LAST OFFPAGE TRUE
J 0
(-1900 4275);
DISPLAY 0.872340 (-1900 4275);
PAINT GREEN (-1900 4275);
DISPLAY INVISIBLE (-1900 4275);
FORCEPROP 2 LAST CDS_LIB standard
J 0
(-2225 4400);
DISPLAY INVISIBLE (-2225 4400);
FORCEPROP 2 LAST PATH I1942
J 0
(-2025 4450);
DISPLAY 0.680851 (-2025 4450);
DISPLAY INVISIBLE (-2025 4450);
FORCEADD OFFPAGE..1
R 2
(-2225 4350);
FORCEPROP 2 LAST $XR0 140 
J 0
(-2039 4350);
DISPLAY 0.638298 (-2039 4350);
PAINT MONO (-2039 4350);
FORCEPROP 1 LAST COMMENT_BODY TRUE
J 2
(-2350 4250);
DISPLAY 0.872340 (-2350 4250);
PAINT GREEN (-2350 4250);
DISPLAY INVISIBLE (-2350 4250);
FORCEPROP 1 LAST OFFPAGE TRUE
J 2
(-2550 4225);
DISPLAY 0.872340 (-2550 4225);
PAINT GREEN (-2550 4225);
DISPLAY INVISIBLE (-2550 4225);
FORCEPROP 2 LAST CDS_LIB standard
J 0
(-2225 4350);
DISPLAY INVISIBLE (-2225 4350);
FORCEPROP 2 LAST PATH I1943
J 0
(-2025 4400);
DISPLAY 0.680851 (-2025 4400);
DISPLAY INVISIBLE (-2025 4400);
FORCEADD OFFPAGE..1
R 2
(-2225 4250);
FORCEPROP 2 LAST $XR0 140 
J 0
(-2039 4250);
DISPLAY 0.638298 (-2039 4250);
PAINT MONO (-2039 4250);
FORCEPROP 1 LAST COMMENT_BODY TRUE
J 2
(-2350 4150);
DISPLAY 0.872340 (-2350 4150);
PAINT GREEN (-2350 4150);
DISPLAY INVISIBLE (-2350 4150);
FORCEPROP 1 LAST OFFPAGE TRUE
J 2
(-2550 4125);
DISPLAY 0.872340 (-2550 4125);
PAINT GREEN (-2550 4125);
DISPLAY INVISIBLE (-2550 4125);
FORCEPROP 2 LAST CDS_LIB standard
J 0
(-2225 4250);
DISPLAY INVISIBLE (-2225 4250);
FORCEPROP 2 LAST PATH I1944
J 0
(-2025 4300);
DISPLAY 0.680851 (-2025 4300);
DISPLAY INVISIBLE (-2025 4300);
FORCEADD OFFPAGE..1
R 2
(-2225 3700);
FORCEPROP 2 LAST $XR0 144 
J 0
(-2039 3700);
DISPLAY 0.638298 (-2039 3700);
PAINT MONO (-2039 3700);
FORCEPROP 1 LAST COMMENT_BODY TRUE
J 2
(-2350 3600);
DISPLAY 0.872340 (-2350 3600);
PAINT GREEN (-2350 3600);
DISPLAY INVISIBLE (-2350 3600);
FORCEPROP 1 LAST OFFPAGE TRUE
J 2
(-2550 3575);
DISPLAY 0.872340 (-2550 3575);
PAINT GREEN (-2550 3575);
DISPLAY INVISIBLE (-2550 3575);
FORCEPROP 2 LAST CDS_LIB standard
J 0
(-2225 3700);
DISPLAY INVISIBLE (-2225 3700);
FORCEPROP 2 LAST PATH I1945
J 0
(-2025 3750);
DISPLAY 0.680851 (-2025 3750);
DISPLAY INVISIBLE (-2025 3750);
FORCEADD OFFPAGE..2
(-2225 3800);
FORCEPROP 2 LAST $XR0 83 
J 0
(-2036 3800);
DISPLAY 0.638298 (-2036 3800);
PAINT MONO (-2036 3800);
FORCEPROP 1 LAST COMMENT_BODY TRUE
J 0
(-2270 3705);
DISPLAY 0.872340 (-2270 3705);
PAINT GREEN (-2270 3705);
DISPLAY INVISIBLE (-2270 3705);
FORCEPROP 1 LAST OFFPAGE TRUE
J 0
(-1900 3675);
DISPLAY 0.872340 (-1900 3675);
PAINT GREEN (-1900 3675);
DISPLAY INVISIBLE (-1900 3675);
FORCEPROP 2 LAST CDS_LIB standard
J 0
(-2225 3800);
DISPLAY INVISIBLE (-2225 3800);
FORCEPROP 2 LAST PATH I1946
J 0
(-2025 3850);
DISPLAY 0.680851 (-2025 3850);
DISPLAY INVISIBLE (-2025 3850);
FORCEADD OFFPAGE..2
(-2225 3850);
FORCEPROP 2 LAST $XR0 28 
J 0
(-2036 3850);
DISPLAY 0.638298 (-2036 3850);
PAINT MONO (-2036 3850);
FORCEPROP 1 LAST COMMENT_BODY TRUE
J 0
(-2270 3755);
DISPLAY 0.872340 (-2270 3755);
PAINT GREEN (-2270 3755);
DISPLAY INVISIBLE (-2270 3755);
FORCEPROP 1 LAST OFFPAGE TRUE
J 0
(-1900 3725);
DISPLAY 0.872340 (-1900 3725);
PAINT GREEN (-1900 3725);
DISPLAY INVISIBLE (-1900 3725);
FORCEPROP 2 LAST CDS_LIB standard
J 0
(-2225 3850);
DISPLAY INVISIBLE (-2225 3850);
FORCEPROP 2 LAST PATH I1947
J 0
(-2025 3900);
DISPLAY 0.680851 (-2025 3900);
DISPLAY INVISIBLE (-2025 3900);
FORCEADD OFFPAGE..1
R 2
(-2225 4050);
FORCEPROP 2 LAST $XR0 144 
J 0
(-2039 4050);
DISPLAY 0.638298 (-2039 4050);
PAINT MONO (-2039 4050);
FORCEPROP 1 LAST COMMENT_BODY TRUE
J 2
(-2350 3950);
DISPLAY 0.872340 (-2350 3950);
PAINT GREEN (-2350 3950);
DISPLAY INVISIBLE (-2350 3950);
FORCEPROP 1 LAST OFFPAGE TRUE
J 2
(-2550 3925);
DISPLAY 0.872340 (-2550 3925);
PAINT GREEN (-2550 3925);
DISPLAY INVISIBLE (-2550 3925);
FORCEPROP 2 LAST CDS_LIB standard
J 0
(-2225 4050);
DISPLAY INVISIBLE (-2225 4050);
FORCEPROP 2 LAST PATH I1948
J 0
(-2025 4100);
DISPLAY 0.680851 (-2025 4100);
DISPLAY INVISIBLE (-2025 4100);
FORCEADD OFFPAGE..1
R 2
(-2225 4200);
FORCEPROP 2 LAST $XR0 144 
J 0
(-2039 4200);
DISPLAY 0.638298 (-2039 4200);
PAINT MONO (-2039 4200);
FORCEPROP 2 LAST CDS_LIB standard
J 0
(-2225 4200);
DISPLAY INVISIBLE (-2225 4200);
FORCEPROP 2 LAST PATH I1949
J 0
(-2025 4250);
DISPLAY 0.680851 (-2025 4250);
DISPLAY INVISIBLE (-2025 4250);
FORCEPROP 1 LAST OFFPAGE TRUE
J 2
(-2550 4075);
DISPLAY 0.872340 (-2550 4075);
PAINT GREEN (-2550 4075);
DISPLAY INVISIBLE (-2550 4075);
FORCEPROP 1 LAST COMMENT_BODY TRUE
J 2
(-2350 4100);
DISPLAY 0.872340 (-2350 4100);
PAINT GREEN (-2350 4100);
DISPLAY INVISIBLE (-2350 4100);
FORCEADD OFFPAGE..2
(-2225 4000);
FORCEPROP 2 LAST $XR0 151 
J 0
(-2036 4000);
DISPLAY 0.638298 (-2036 4000);
PAINT MONO (-2036 4000);
FORCEPROP 2 LAST CDS_LIB standard
J 0
(-2225 4000);
DISPLAY INVISIBLE (-2225 4000);
FORCEPROP 2 LAST PATH I1950
J 0
(-2025 4050);
DISPLAY 0.680851 (-2025 4050);
DISPLAY INVISIBLE (-2025 4050);
FORCEPROP 1 LAST OFFPAGE TRUE
J 0
(-1900 3875);
DISPLAY 0.872340 (-1900 3875);
PAINT GREEN (-1900 3875);
DISPLAY INVISIBLE (-1900 3875);
FORCEPROP 1 LAST COMMENT_BODY TRUE
J 0
(-2270 3905);
DISPLAY 0.872340 (-2270 3905);
PAINT GREEN (-2270 3905);
DISPLAY INVISIBLE (-2270 3905);
FORCEADD Q_RES..1
(-3150 4650);
FORCEPROP 1 LAST LOCATION R588
J 0
(-3025 4650);
DISPLAY 0.489362 (-3025 4650);
PAINT SKYBLUE (-3025 4650);
FORCEPROP 0 LAST $SEC 1
J 0
(-3200 4750);
DISPLAY 0.680851 (-3200 4750);
PAINT MONO (-3200 4750);
DISPLAY INVISIBLE (-3200 4750);
FORCEPROP 0 LAST CDS_SEC 1
J 0
(-3200 4750);
DISPLAY 1.021277 (-3200 4750);
DISPLAY INVISIBLE (-3200 4750);
FORCEPROP 1 LASTPIN (-3250 4650) $PN 1
J 0
(-3238 4662);
DISPLAY 0.489362 (-3238 4662);
PAINT MONO (-3238 4662);
FORCEPROP 1 LASTPIN (-3050 4650) $PN 2
J 0
(-3088 4662);
DISPLAY 0.489362 (-3088 4662);
PAINT MONO (-3088 4662);
FORCEPROP 1 LAST VALUE 33
J 2
(-3275 4650);
DISPLAY 0.489362 (-3275 4650);
PAINT SKYBLUE (-3275 4650);
FORCEPROP 2 LAST ROOM RST_CPU0_PLD_TO_DIMM
J 2
(-3125 4750);
DISPLAY 0.744681 (-3125 4750);
PAINT RED (-3125 4750);
DISPLAY INVISIBLE (-3125 4750);
FORCEPROP 1 LAST PACK_TYPE 0402LF
J 2
(-2975 4575);
DISPLAY 0.489362 (-2975 4575);
PAINT SKYBLUE (-2975 4575);
DISPLAY INVISIBLE (-2975 4575);
FORCEPROP 1 LAST PART_NUMBER CS03302JB29
J 2
(-3050 4700);
DISPLAY 0.489362 (-3050 4700);
PAINT SKYBLUE (-3050 4700);
DISPLAY INVISIBLE (-3050 4700);
FORCEPROP 1 LAST TOLERANCE 5%
J 0
(-3275 4625);
DISPLAY 0.489362 (-3275 4625);
PAINT SKYBLUE (-3275 4625);
DISPLAY INVISIBLE (-3275 4625);
FORCEPROP 1 LAST MATERIAL CHIP
J 2
(-2975 4625);
DISPLAY 0.489362 (-2975 4625);
PAINT SKYBLUE (-2975 4625);
DISPLAY INVISIBLE (-2975 4625);
FORCEPROP 1 LAST WATTAGE 1/16W
J 2
(-3225 4575);
DISPLAY 0.489362 (-3225 4575);
PAINT SKYBLUE (-3225 4575);
DISPLAY INVISIBLE (-3225 4575);
FORCEPROP 1 LAST PATH I1951
J 0
(-3200 4800);
DISPLAY 0.978723 (-3200 4800);
PAINT WHITE (-3200 4800);
DISPLAY INVISIBLE (-3200 4800);
FORCEPROP 2 LAST BOM_COST MEM
J 2
(-3125 4800);
DISPLAY 0.744681 (-3125 4800);
PAINT WHITE (-3125 4800);
DISPLAY INVISIBLE (-3125 4800);
FORCEPROP 2 LAST CDS_LIB pure_quanta
J 0
(-3150 4650);
DISPLAY INVISIBLE (-3150 4650);
FORCEADD Q_RES..1
(-3150 4550);
FORCEPROP 1 LAST LOCATION R251
J 0
(-3025 4550);
DISPLAY 0.489362 (-3025 4550);
PAINT SKYBLUE (-3025 4550);
FORCEPROP 0 LAST $SEC 1
J 2
(-3025 4600);
DISPLAY 0.680851 (-3025 4600);
PAINT MONO (-3025 4600);
DISPLAY INVISIBLE (-3025 4600);
FORCEPROP 0 LAST CDS_SEC 1
J 2
(-3025 4600);
DISPLAY 1.021277 (-3025 4600);
DISPLAY INVISIBLE (-3025 4600);
FORCEPROP 1 LASTPIN (-3250 4550) $PN 1
J 0
(-3238 4562);
DISPLAY 0.489362 (-3238 4562);
PAINT MONO (-3238 4562);
FORCEPROP 1 LASTPIN (-3050 4550) $PN 2
J 0
(-3088 4562);
DISPLAY 0.489362 (-3088 4562);
PAINT MONO (-3088 4562);
FORCEPROP 1 LAST VALUE 0
J 2
(-3275 4550);
DISPLAY 0.489362 (-3275 4550);
PAINT SKYBLUE (-3275 4550);
FORCEPROP 2 LAST ROOM RST_CPU0_PLD_TO_DIMM
J 2
(-3125 4650);
DISPLAY 0.744681 (-3125 4650);
PAINT RED (-3125 4650);
DISPLAY INVISIBLE (-3125 4650);
FORCEPROP 1 LAST PACK_TYPE 0402LF
J 2
(-2975 4475);
DISPLAY 0.489362 (-2975 4475);
PAINT SKYBLUE (-2975 4475);
DISPLAY INVISIBLE (-2975 4475);
FORCEPROP 1 LAST PART_NUMBER CS00002JB38
J 2
(-3050 4600);
DISPLAY 0.489362 (-3050 4600);
PAINT SKYBLUE (-3050 4600);
DISPLAY INVISIBLE (-3050 4600);
FORCEPROP 1 LAST TOLERANCE 5%
J 0
(-3275 4525);
DISPLAY 0.489362 (-3275 4525);
PAINT SKYBLUE (-3275 4525);
DISPLAY INVISIBLE (-3275 4525);
FORCEPROP 1 LAST MATERIAL CHIP
J 2
(-2975 4525);
DISPLAY 0.489362 (-2975 4525);
PAINT SKYBLUE (-2975 4525);
DISPLAY INVISIBLE (-2975 4525);
FORCEPROP 1 LAST WATTAGE 1/16W
J 2
(-3225 4475);
DISPLAY 0.489362 (-3225 4475);
PAINT SKYBLUE (-3225 4475);
DISPLAY INVISIBLE (-3225 4475);
FORCEPROP 1 LAST PATH I1952
J 0
(-3200 4700);
DISPLAY 0.978723 (-3200 4700);
PAINT WHITE (-3200 4700);
DISPLAY INVISIBLE (-3200 4700);
FORCEPROP 2 LAST BOM_COST MEM
J 2
(-3125 4700);
DISPLAY 0.744681 (-3125 4700);
PAINT WHITE (-3125 4700);
DISPLAY INVISIBLE (-3125 4700);
FORCEPROP 2 LAST CDS_LIB pure_quanta
J 2
(-3150 4550);
DISPLAY INVISIBLE (-3150 4550);
FORCEADD Q_RES..1
(-3150 4500);
FORCEPROP 1 LAST LOCATION R173
J 0
(-3025 4500);
DISPLAY 0.489362 (-3025 4500);
PAINT SKYBLUE (-3025 4500);
FORCEPROP 0 LAST $SEC 1
J 2
(-3025 4550);
DISPLAY 0.680851 (-3025 4550);
PAINT MONO (-3025 4550);
DISPLAY INVISIBLE (-3025 4550);
FORCEPROP 0 LAST CDS_SEC 1
J 2
(-3025 4550);
DISPLAY 1.021277 (-3025 4550);
DISPLAY INVISIBLE (-3025 4550);
FORCEPROP 1 LASTPIN (-3250 4500) $PN 1
J 0
(-3238 4512);
DISPLAY 0.489362 (-3238 4512);
PAINT MONO (-3238 4512);
FORCEPROP 1 LASTPIN (-3050 4500) $PN 2
J 0
(-3088 4512);
DISPLAY 0.489362 (-3088 4512);
PAINT MONO (-3088 4512);
FORCEPROP 1 LAST VALUE 33
J 2
(-3275 4500);
DISPLAY 0.489362 (-3275 4500);
PAINT SKYBLUE (-3275 4500);
FORCEPROP 2 LAST ROOM RST_CPU0_PLD_TO_DIMM
J 2
(-3125 4600);
DISPLAY 0.744681 (-3125 4600);
PAINT RED (-3125 4600);
DISPLAY INVISIBLE (-3125 4600);
FORCEPROP 1 LAST PACK_TYPE 0402LF
J 2
(-2975 4425);
DISPLAY 0.489362 (-2975 4425);
PAINT SKYBLUE (-2975 4425);
DISPLAY INVISIBLE (-2975 4425);
FORCEPROP 1 LAST PART_NUMBER CS03302JB29
J 2
(-3050 4550);
DISPLAY 0.489362 (-3050 4550);
PAINT SKYBLUE (-3050 4550);
DISPLAY INVISIBLE (-3050 4550);
FORCEPROP 1 LAST TOLERANCE 5%
J 0
(-3275 4475);
DISPLAY 0.489362 (-3275 4475);
PAINT SKYBLUE (-3275 4475);
DISPLAY INVISIBLE (-3275 4475);
FORCEPROP 1 LAST MATERIAL CHIP
J 2
(-2975 4475);
DISPLAY 0.489362 (-2975 4475);
PAINT SKYBLUE (-2975 4475);
DISPLAY INVISIBLE (-2975 4475);
FORCEPROP 1 LAST WATTAGE 1/16W
J 2
(-3225 4425);
DISPLAY 0.489362 (-3225 4425);
PAINT SKYBLUE (-3225 4425);
DISPLAY INVISIBLE (-3225 4425);
FORCEPROP 1 LAST PATH I1953
J 0
(-3200 4650);
DISPLAY 0.978723 (-3200 4650);
PAINT WHITE (-3200 4650);
DISPLAY INVISIBLE (-3200 4650);
FORCEPROP 2 LAST CDS_LIB pure_quanta
J 2
(-3150 4500);
DISPLAY INVISIBLE (-3150 4500);
FORCEPROP 2 LAST BOM_COST MEM
J 2
(-3125 4650);
DISPLAY 0.744681 (-3125 4650);
PAINT WHITE (-3125 4650);
DISPLAY INVISIBLE (-3125 4650);
FORCEADD Q_RES..1
(-3150 4450);
FORCEPROP 1 LAST LOCATION R161
J 0
(-3025 4450);
DISPLAY 0.489362 (-3025 4450);
PAINT SKYBLUE (-3025 4450);
FORCEPROP 0 LAST $SEC 1
J 2
(-3025 4500);
DISPLAY 0.680851 (-3025 4500);
PAINT MONO (-3025 4500);
DISPLAY INVISIBLE (-3025 4500);
FORCEPROP 0 LAST CDS_SEC 1
J 2
(-3025 4500);
DISPLAY 1.021277 (-3025 4500);
DISPLAY INVISIBLE (-3025 4500);
FORCEPROP 1 LASTPIN (-3250 4450) $PN 1
J 0
(-3238 4462);
DISPLAY 0.489362 (-3238 4462);
PAINT MONO (-3238 4462);
FORCEPROP 1 LASTPIN (-3050 4450) $PN 2
J 0
(-3088 4462);
DISPLAY 0.489362 (-3088 4462);
PAINT MONO (-3088 4462);
FORCEPROP 1 LAST VALUE 33
J 2
(-3275 4450);
DISPLAY 0.489362 (-3275 4450);
PAINT SKYBLUE (-3275 4450);
FORCEPROP 2 LAST ROOM RST_CPU0_PLD_TO_DIMM
J 2
(-3125 4550);
DISPLAY 0.744681 (-3125 4550);
PAINT RED (-3125 4550);
DISPLAY INVISIBLE (-3125 4550);
FORCEPROP 1 LAST PACK_TYPE 0402LF
J 2
(-2975 4375);
DISPLAY 0.489362 (-2975 4375);
PAINT SKYBLUE (-2975 4375);
DISPLAY INVISIBLE (-2975 4375);
FORCEPROP 1 LAST PART_NUMBER CS03302JB29
J 2
(-3050 4500);
DISPLAY 0.489362 (-3050 4500);
PAINT SKYBLUE (-3050 4500);
DISPLAY INVISIBLE (-3050 4500);
FORCEPROP 1 LAST TOLERANCE 5%
J 0
(-3275 4425);
DISPLAY 0.489362 (-3275 4425);
PAINT SKYBLUE (-3275 4425);
DISPLAY INVISIBLE (-3275 4425);
FORCEPROP 1 LAST MATERIAL CHIP
J 2
(-2975 4425);
DISPLAY 0.489362 (-2975 4425);
PAINT SKYBLUE (-2975 4425);
DISPLAY INVISIBLE (-2975 4425);
FORCEPROP 1 LAST WATTAGE 1/16W
J 2
(-3225 4375);
DISPLAY 0.489362 (-3225 4375);
PAINT SKYBLUE (-3225 4375);
DISPLAY INVISIBLE (-3225 4375);
FORCEPROP 1 LAST PATH I1954
J 0
(-3200 4600);
DISPLAY 0.978723 (-3200 4600);
PAINT WHITE (-3200 4600);
DISPLAY INVISIBLE (-3200 4600);
FORCEPROP 2 LAST BOM_COST MEM
J 2
(-3125 4600);
DISPLAY 0.744681 (-3125 4600);
PAINT WHITE (-3125 4600);
DISPLAY INVISIBLE (-3125 4600);
FORCEPROP 2 LAST CDS_LIB pure_quanta
J 2
(-3150 4450);
DISPLAY INVISIBLE (-3150 4450);
FORCEADD Q_RES..1
(-3150 4400);
FORCEPROP 1 LAST LOCATION R174
J 0
(-3025 4400);
DISPLAY 0.489362 (-3025 4400);
PAINT SKYBLUE (-3025 4400);
FORCEPROP 0 LAST $SEC 1
J 0
(-3025 4450);
DISPLAY 0.680851 (-3025 4450);
PAINT MONO (-3025 4450);
DISPLAY INVISIBLE (-3025 4450);
FORCEPROP 0 LAST CDS_SEC 1
J 0
(-3025 4450);
DISPLAY 0.680851 (-3025 4450);
DISPLAY INVISIBLE (-3025 4450);
FORCEPROP 1 LASTPIN (-3250 4400) $PN 1
J 0
(-3238 4412);
DISPLAY 0.489362 (-3238 4412);
PAINT MONO (-3238 4412);
FORCEPROP 1 LASTPIN (-3050 4400) $PN 2
J 0
(-3088 4412);
DISPLAY 0.489362 (-3088 4412);
PAINT MONO (-3088 4412);
FORCEPROP 1 LAST VALUE 33
J 2
(-3275 4400);
DISPLAY 0.489362 (-3275 4400);
PAINT SKYBLUE (-3275 4400);
FORCEPROP 2 LAST ROOM RST_CPU0_PLD_TO_DIMM
J 2
(-3125 4500);
DISPLAY 0.744681 (-3125 4500);
PAINT RED (-3125 4500);
DISPLAY INVISIBLE (-3125 4500);
FORCEPROP 1 LAST PACK_TYPE 0402LF
J 2
(-2975 4325);
DISPLAY 0.489362 (-2975 4325);
PAINT SKYBLUE (-2975 4325);
DISPLAY INVISIBLE (-2975 4325);
FORCEPROP 1 LAST PART_NUMBER CS03302JB29
J 2
(-3050 4450);
DISPLAY 0.489362 (-3050 4450);
PAINT SKYBLUE (-3050 4450);
DISPLAY INVISIBLE (-3050 4450);
FORCEPROP 1 LAST TOLERANCE 5%
J 0
(-3275 4375);
DISPLAY 0.489362 (-3275 4375);
PAINT SKYBLUE (-3275 4375);
DISPLAY INVISIBLE (-3275 4375);
FORCEPROP 1 LAST MATERIAL CHIP
J 2
(-2975 4375);
DISPLAY 0.489362 (-2975 4375);
PAINT SKYBLUE (-2975 4375);
DISPLAY INVISIBLE (-2975 4375);
FORCEPROP 1 LAST WATTAGE 1/16W
J 2
(-3225 4325);
DISPLAY 0.489362 (-3225 4325);
PAINT SKYBLUE (-3225 4325);
DISPLAY INVISIBLE (-3225 4325);
FORCEPROP 1 LAST PATH I1955
J 0
(-3200 4550);
DISPLAY 0.978723 (-3200 4550);
PAINT WHITE (-3200 4550);
DISPLAY INVISIBLE (-3200 4550);
FORCEPROP 2 LAST BOM_COST MEM
J 2
(-3125 4550);
DISPLAY 0.744681 (-3125 4550);
PAINT WHITE (-3125 4550);
DISPLAY INVISIBLE (-3125 4550);
FORCEPROP 2 LAST CDS_LIB pure_quanta
J 0
(-3150 4400);
DISPLAY INVISIBLE (-3150 4400);
FORCEADD Q_RES..1
(-3150 4300);
FORCEPROP 1 LAST LOCATION R372
J 0
(-3025 4300);
DISPLAY 0.489362 (-3025 4300);
PAINT SKYBLUE (-3025 4300);
FORCEPROP 0 LAST $SEC 1
J 0
(-3025 4350);
DISPLAY 0.680851 (-3025 4350);
PAINT MONO (-3025 4350);
DISPLAY INVISIBLE (-3025 4350);
FORCEPROP 0 LAST CDS_SEC 1
J 0
(-3025 4350);
DISPLAY 0.680851 (-3025 4350);
DISPLAY INVISIBLE (-3025 4350);
FORCEPROP 1 LASTPIN (-3250 4300) $PN 1
J 0
(-3238 4312);
DISPLAY 0.489362 (-3238 4312);
PAINT MONO (-3238 4312);
FORCEPROP 1 LASTPIN (-3050 4300) $PN 2
J 0
(-3088 4312);
DISPLAY 0.489362 (-3088 4312);
PAINT MONO (-3088 4312);
FORCEPROP 1 LAST VALUE 33
J 2
(-3275 4300);
DISPLAY 0.489362 (-3275 4300);
PAINT SKYBLUE (-3275 4300);
FORCEPROP 2 LAST CDS_LIB pure_quanta
J 0
(-3150 4300);
DISPLAY INVISIBLE (-3150 4300);
FORCEPROP 1 LAST PATH I1956
J 0
(-3200 4450);
DISPLAY 0.978723 (-3200 4450);
PAINT WHITE (-3200 4450);
DISPLAY INVISIBLE (-3200 4450);
FORCEPROP 2 LAST BOM_COST MEM
J 2
(-3125 4450);
DISPLAY 0.744681 (-3125 4450);
PAINT WHITE (-3125 4450);
DISPLAY INVISIBLE (-3125 4450);
FORCEPROP 1 LAST WATTAGE 1/16W
J 2
(-3225 4225);
DISPLAY 0.489362 (-3225 4225);
PAINT SKYBLUE (-3225 4225);
DISPLAY INVISIBLE (-3225 4225);
FORCEPROP 1 LAST MATERIAL CHIP
J 2
(-2975 4275);
DISPLAY 0.489362 (-2975 4275);
PAINT SKYBLUE (-2975 4275);
DISPLAY INVISIBLE (-2975 4275);
FORCEPROP 1 LAST TOLERANCE 5%
J 0
(-3275 4275);
DISPLAY 0.489362 (-3275 4275);
PAINT SKYBLUE (-3275 4275);
DISPLAY INVISIBLE (-3275 4275);
FORCEPROP 1 LAST PART_NUMBER CS03302JB29
J 2
(-3050 4350);
DISPLAY 0.489362 (-3050 4350);
PAINT SKYBLUE (-3050 4350);
DISPLAY INVISIBLE (-3050 4350);
FORCEPROP 1 LAST PACK_TYPE 0402LF
J 2
(-2975 4225);
DISPLAY 0.489362 (-2975 4225);
PAINT SKYBLUE (-2975 4225);
DISPLAY INVISIBLE (-2975 4225);
FORCEPROP 2 LAST ROOM RST_CPU0_PLD_TO_DIMM
J 2
(-3125 4400);
DISPLAY 0.744681 (-3125 4400);
PAINT RED (-3125 4400);
DISPLAY INVISIBLE (-3125 4400);
FORCEADD Q_RES..1
(-3150 4200);
FORCEPROP 1 LAST LOCATION R1359
J 0
(-3025 4200);
DISPLAY 0.489362 (-3025 4200);
PAINT SKYBLUE (-3025 4200);
FORCEPROP 0 LAST $SEC 1
J 0
(-3025 4250);
DISPLAY 0.680851 (-3025 4250);
PAINT MONO (-3025 4250);
DISPLAY INVISIBLE (-3025 4250);
FORCEPROP 0 LAST CDS_SEC 1
J 0
(-3025 4250);
DISPLAY 0.680851 (-3025 4250);
DISPLAY INVISIBLE (-3025 4250);
FORCEPROP 1 LASTPIN (-3250 4200) $PN 1
J 0
(-3238 4212);
DISPLAY 0.489362 (-3238 4212);
PAINT MONO (-3238 4212);
FORCEPROP 1 LASTPIN (-3050 4200) $PN 2
J 0
(-3088 4212);
DISPLAY 0.489362 (-3088 4212);
PAINT MONO (-3088 4212);
FORCEPROP 1 LAST VALUE 0
J 2
(-3275 4200);
DISPLAY 0.489362 (-3275 4200);
PAINT SKYBLUE (-3275 4200);
FORCEPROP 2 LAST ROOM RST_CPU0_PLD_TO_DIMM
J 2
(-3125 4300);
DISPLAY 0.744681 (-3125 4300);
PAINT RED (-3125 4300);
DISPLAY INVISIBLE (-3125 4300);
FORCEPROP 1 LAST PACK_TYPE 0402LF
J 2
(-2975 4125);
DISPLAY 0.489362 (-2975 4125);
PAINT SKYBLUE (-2975 4125);
DISPLAY INVISIBLE (-2975 4125);
FORCEPROP 1 LAST PART_NUMBER CS00002JB38
J 2
(-3050 4250);
DISPLAY 0.489362 (-3050 4250);
PAINT SKYBLUE (-3050 4250);
DISPLAY INVISIBLE (-3050 4250);
FORCEPROP 1 LAST TOLERANCE 5%
J 0
(-3275 4175);
DISPLAY 0.489362 (-3275 4175);
PAINT SKYBLUE (-3275 4175);
DISPLAY INVISIBLE (-3275 4175);
FORCEPROP 1 LAST MATERIAL CHIP
J 2
(-2975 4175);
DISPLAY 0.489362 (-2975 4175);
PAINT SKYBLUE (-2975 4175);
DISPLAY INVISIBLE (-2975 4175);
FORCEPROP 1 LAST WATTAGE 1/16W
J 2
(-3225 4125);
DISPLAY 0.489362 (-3225 4125);
PAINT SKYBLUE (-3225 4125);
DISPLAY INVISIBLE (-3225 4125);
FORCEPROP 1 LAST PATH I1957
J 0
(-3200 4350);
DISPLAY 0.978723 (-3200 4350);
PAINT WHITE (-3200 4350);
DISPLAY INVISIBLE (-3200 4350);
FORCEPROP 2 LAST CDS_LIB pure_quanta
J 0
(-3150 4200);
DISPLAY INVISIBLE (-3150 4200);
FORCEPROP 2 LAST BOM_COST MEM
J 2
(-3125 4350);
DISPLAY 0.744681 (-3125 4350);
PAINT WHITE (-3125 4350);
DISPLAY INVISIBLE (-3125 4350);
FORCEADD Q_RES..1
(-3150 4050);
FORCEPROP 1 LAST LOCATION R395
J 0
(-3025 4050);
DISPLAY 0.489362 (-3025 4050);
PAINT SKYBLUE (-3025 4050);
FORCEPROP 0 LAST $SEC 1
J 0
(-3025 4100);
DISPLAY 0.680851 (-3025 4100);
PAINT MONO (-3025 4100);
DISPLAY INVISIBLE (-3025 4100);
FORCEPROP 0 LAST CDS_SEC 1
J 0
(-3025 4100);
DISPLAY 0.680851 (-3025 4100);
DISPLAY INVISIBLE (-3025 4100);
FORCEPROP 1 LASTPIN (-3250 4050) $PN 1
J 0
(-3238 4062);
DISPLAY 0.489362 (-3238 4062);
PAINT MONO (-3238 4062);
FORCEPROP 1 LASTPIN (-3050 4050) $PN 2
J 0
(-3088 4062);
DISPLAY 0.489362 (-3088 4062);
PAINT MONO (-3088 4062);
FORCEPROP 1 LAST VALUE 0
J 2
(-3275 4050);
DISPLAY 0.489362 (-3275 4050);
PAINT SKYBLUE (-3275 4050);
FORCEPROP 2 LAST CDS_LIB pure_quanta
J 0
(-3150 4050);
DISPLAY INVISIBLE (-3150 4050);
FORCEPROP 1 LAST PATH I1958
J 0
(-3200 4200);
DISPLAY 0.978723 (-3200 4200);
PAINT WHITE (-3200 4200);
DISPLAY INVISIBLE (-3200 4200);
FORCEPROP 2 LAST BOM_COST MEM
J 2
(-3125 4200);
DISPLAY 0.744681 (-3125 4200);
PAINT WHITE (-3125 4200);
DISPLAY INVISIBLE (-3125 4200);
FORCEPROP 1 LAST WATTAGE 1/16W
J 2
(-3225 3975);
DISPLAY 0.489362 (-3225 3975);
PAINT SKYBLUE (-3225 3975);
DISPLAY INVISIBLE (-3225 3975);
FORCEPROP 1 LAST MATERIAL CHIP
J 2
(-2975 4025);
DISPLAY 0.489362 (-2975 4025);
PAINT SKYBLUE (-2975 4025);
DISPLAY INVISIBLE (-2975 4025);
FORCEPROP 1 LAST TOLERANCE 5%
J 0
(-3275 4025);
DISPLAY 0.489362 (-3275 4025);
PAINT SKYBLUE (-3275 4025);
DISPLAY INVISIBLE (-3275 4025);
FORCEPROP 1 LAST PART_NUMBER CS00002JB38
J 2
(-3050 4100);
DISPLAY 0.489362 (-3050 4100);
PAINT SKYBLUE (-3050 4100);
DISPLAY INVISIBLE (-3050 4100);
FORCEPROP 1 LAST PACK_TYPE 0402LF
J 2
(-2975 3975);
DISPLAY 0.489362 (-2975 3975);
PAINT SKYBLUE (-2975 3975);
DISPLAY INVISIBLE (-2975 3975);
FORCEPROP 2 LAST ROOM RST_CPU0_PLD_TO_DIMM
J 2
(-3125 4150);
DISPLAY 0.744681 (-3125 4150);
PAINT RED (-3125 4150);
DISPLAY INVISIBLE (-3125 4150);
FORCEADD Q_RES..1
(-3150 4000);
FORCEPROP 1 LAST LOCATION R158
J 0
(-3025 4000);
DISPLAY 0.489362 (-3025 4000);
PAINT SKYBLUE (-3025 4000);
FORCEPROP 0 LAST $SEC 1
J 2
(-3025 4050);
DISPLAY 0.680851 (-3025 4050);
PAINT MONO (-3025 4050);
DISPLAY INVISIBLE (-3025 4050);
FORCEPROP 0 LAST CDS_SEC 1
J 2
(-3025 4050);
DISPLAY 1.021277 (-3025 4050);
DISPLAY INVISIBLE (-3025 4050);
FORCEPROP 1 LASTPIN (-3250 4000) $PN 1
J 0
(-3238 4012);
DISPLAY 0.489362 (-3238 4012);
PAINT MONO (-3238 4012);
FORCEPROP 1 LASTPIN (-3050 4000) $PN 2
J 0
(-3088 4012);
DISPLAY 0.489362 (-3088 4012);
PAINT MONO (-3088 4012);
FORCEPROP 1 LAST VALUE 33
J 2
(-3275 4000);
DISPLAY 0.489362 (-3275 4000);
PAINT SKYBLUE (-3275 4000);
FORCEPROP 2 LAST ROOM RST_CPU0_PLD_TO_DIMM
J 2
(-3125 4100);
DISPLAY 0.744681 (-3125 4100);
PAINT RED (-3125 4100);
DISPLAY INVISIBLE (-3125 4100);
FORCEPROP 1 LAST PACK_TYPE 0402LF
J 2
(-2975 3925);
DISPLAY 0.489362 (-2975 3925);
PAINT SKYBLUE (-2975 3925);
DISPLAY INVISIBLE (-2975 3925);
FORCEPROP 1 LAST PART_NUMBER CS03302JB29
J 2
(-3050 4050);
DISPLAY 0.489362 (-3050 4050);
PAINT SKYBLUE (-3050 4050);
DISPLAY INVISIBLE (-3050 4050);
FORCEPROP 1 LAST TOLERANCE 5%
J 0
(-3275 3975);
DISPLAY 0.489362 (-3275 3975);
PAINT SKYBLUE (-3275 3975);
DISPLAY INVISIBLE (-3275 3975);
FORCEPROP 1 LAST MATERIAL CHIP
J 2
(-2975 3975);
DISPLAY 0.489362 (-2975 3975);
PAINT SKYBLUE (-2975 3975);
DISPLAY INVISIBLE (-2975 3975);
FORCEPROP 1 LAST WATTAGE 1/16W
J 2
(-3225 3925);
DISPLAY 0.489362 (-3225 3925);
PAINT SKYBLUE (-3225 3925);
DISPLAY INVISIBLE (-3225 3925);
FORCEPROP 1 LAST PATH I1959
J 0
(-3200 4150);
DISPLAY 0.978723 (-3200 4150);
PAINT WHITE (-3200 4150);
DISPLAY INVISIBLE (-3200 4150);
FORCEPROP 2 LAST BOM_COST MEM
J 2
(-3125 4150);
DISPLAY 0.744681 (-3125 4150);
PAINT WHITE (-3125 4150);
DISPLAY INVISIBLE (-3125 4150);
FORCEPROP 2 LAST CDS_LIB pure_quanta
J 2
(-3150 4000);
DISPLAY INVISIBLE (-3150 4000);
FORCEADD Q_RES..1
(-3150 3850);
FORCEPROP 1 LAST LOCATION R186
J 0
(-3025 3850);
DISPLAY 0.489362 (-3025 3850);
PAINT SKYBLUE (-3025 3850);
FORCEPROP 0 LAST $SEC 1
J 2
(-3025 3900);
DISPLAY 0.680851 (-3025 3900);
PAINT MONO (-3025 3900);
DISPLAY INVISIBLE (-3025 3900);
FORCEPROP 0 LAST CDS_SEC 1
J 2
(-3025 3900);
DISPLAY 1.021277 (-3025 3900);
DISPLAY INVISIBLE (-3025 3900);
FORCEPROP 1 LASTPIN (-3250 3850) $PN 1
J 0
(-3238 3862);
DISPLAY 0.489362 (-3238 3862);
PAINT MONO (-3238 3862);
FORCEPROP 1 LASTPIN (-3050 3850) $PN 2
J 0
(-3088 3862);
DISPLAY 0.489362 (-3088 3862);
PAINT MONO (-3088 3862);
FORCEPROP 1 LAST VALUE 33
J 2
(-3275 3850);
DISPLAY 0.489362 (-3275 3850);
PAINT SKYBLUE (-3275 3850);
FORCEPROP 2 LAST ROOM RST_CPU0_PLD_TO_DIMM
J 2
(-3125 3950);
DISPLAY 0.744681 (-3125 3950);
PAINT RED (-3125 3950);
DISPLAY INVISIBLE (-3125 3950);
FORCEPROP 1 LAST PACK_TYPE 0402LF
J 2
(-2975 3775);
DISPLAY 0.489362 (-2975 3775);
PAINT SKYBLUE (-2975 3775);
DISPLAY INVISIBLE (-2975 3775);
FORCEPROP 1 LAST PART_NUMBER CS03302JB29
J 2
(-3050 3900);
DISPLAY 0.489362 (-3050 3900);
PAINT SKYBLUE (-3050 3900);
DISPLAY INVISIBLE (-3050 3900);
FORCEPROP 1 LAST TOLERANCE 5%
J 0
(-3275 3825);
DISPLAY 0.489362 (-3275 3825);
PAINT SKYBLUE (-3275 3825);
DISPLAY INVISIBLE (-3275 3825);
FORCEPROP 1 LAST MATERIAL CHIP
J 2
(-2975 3825);
DISPLAY 0.489362 (-2975 3825);
PAINT SKYBLUE (-2975 3825);
DISPLAY INVISIBLE (-2975 3825);
FORCEPROP 1 LAST WATTAGE 1/16W
J 2
(-3225 3775);
DISPLAY 0.489362 (-3225 3775);
PAINT SKYBLUE (-3225 3775);
DISPLAY INVISIBLE (-3225 3775);
FORCEPROP 1 LAST PATH I1960
J 0
(-3200 4000);
DISPLAY 0.978723 (-3200 4000);
PAINT WHITE (-3200 4000);
DISPLAY INVISIBLE (-3200 4000);
FORCEPROP 2 LAST BOM_COST MEM
J 2
(-3125 4000);
DISPLAY 0.744681 (-3125 4000);
PAINT WHITE (-3125 4000);
DISPLAY INVISIBLE (-3125 4000);
FORCEPROP 2 LAST CDS_LIB pure_quanta
J 2
(-3150 3850);
DISPLAY INVISIBLE (-3150 3850);
FORCEADD Q_RES..1
(-3150 3800);
FORCEPROP 1 LAST LOCATION R407
J 0
(-3025 3800);
DISPLAY 0.489362 (-3025 3800);
PAINT SKYBLUE (-3025 3800);
FORCEPROP 0 LAST $SEC 1
J 0
(-3025 3825);
DISPLAY 0.680851 (-3025 3825);
PAINT MONO (-3025 3825);
DISPLAY INVISIBLE (-3025 3825);
FORCEPROP 0 LAST CDS_SEC 1
J 0
(-3025 3825);
DISPLAY 0.680851 (-3025 3825);
DISPLAY INVISIBLE (-3025 3825);
FORCEPROP 1 LASTPIN (-3250 3800) $PN 1
J 0
(-3238 3812);
DISPLAY 0.489362 (-3238 3812);
PAINT MONO (-3238 3812);
FORCEPROP 1 LASTPIN (-3050 3800) $PN 2
J 0
(-3088 3812);
DISPLAY 0.489362 (-3088 3812);
PAINT MONO (-3088 3812);
FORCEPROP 1 LAST VALUE 33
J 2
(-3275 3800);
DISPLAY 0.489362 (-3275 3800);
PAINT SKYBLUE (-3275 3800);
FORCEPROP 2 LAST ROOM RST_CPU0_PLD_TO_DIMM
J 2
(-3125 3900);
DISPLAY 0.744681 (-3125 3900);
PAINT RED (-3125 3900);
DISPLAY INVISIBLE (-3125 3900);
FORCEPROP 1 LAST PACK_TYPE 0402LF
J 2
(-2975 3725);
DISPLAY 0.489362 (-2975 3725);
PAINT SKYBLUE (-2975 3725);
DISPLAY INVISIBLE (-2975 3725);
FORCEPROP 1 LAST PART_NUMBER CS03302JB29
J 2
(-3050 3850);
DISPLAY 0.489362 (-3050 3850);
PAINT SKYBLUE (-3050 3850);
DISPLAY INVISIBLE (-3050 3850);
FORCEPROP 1 LAST TOLERANCE 5%
J 0
(-3275 3775);
DISPLAY 0.489362 (-3275 3775);
PAINT SKYBLUE (-3275 3775);
DISPLAY INVISIBLE (-3275 3775);
FORCEPROP 1 LAST MATERIAL CHIP
J 2
(-2975 3775);
DISPLAY 0.489362 (-2975 3775);
PAINT SKYBLUE (-2975 3775);
DISPLAY INVISIBLE (-2975 3775);
FORCEPROP 1 LAST WATTAGE 1/16W
J 2
(-3225 3725);
DISPLAY 0.489362 (-3225 3725);
PAINT SKYBLUE (-3225 3725);
DISPLAY INVISIBLE (-3225 3725);
FORCEPROP 1 LAST PATH I1961
J 0
(-3200 3950);
DISPLAY 0.978723 (-3200 3950);
PAINT WHITE (-3200 3950);
DISPLAY INVISIBLE (-3200 3950);
FORCEPROP 2 LAST BOM_COST MEM
J 2
(-3125 3950);
DISPLAY 0.744681 (-3125 3950);
PAINT WHITE (-3125 3950);
DISPLAY INVISIBLE (-3125 3950);
FORCEPROP 2 LAST CDS_LIB pure_quanta
J 0
(-3150 3800);
DISPLAY INVISIBLE (-3150 3800);
FORCEADD Q_RES..1
(-3150 3700);
FORCEPROP 1 LAST LOCATION R1202
J 0
(-3025 3700);
DISPLAY 0.489362 (-3025 3700);
PAINT SKYBLUE (-3025 3700);
FORCEPROP 0 LAST $SEC 1
J 0
(-3025 3750);
DISPLAY 0.680851 (-3025 3750);
PAINT MONO (-3025 3750);
DISPLAY INVISIBLE (-3025 3750);
FORCEPROP 0 LAST CDS_SEC 1
J 0
(-3025 3750);
DISPLAY 0.680851 (-3025 3750);
DISPLAY INVISIBLE (-3025 3750);
FORCEPROP 1 LASTPIN (-3250 3700) $PN 1
J 0
(-3238 3712);
DISPLAY 0.489362 (-3238 3712);
PAINT MONO (-3238 3712);
FORCEPROP 1 LASTPIN (-3050 3700) $PN 2
J 0
(-3088 3712);
DISPLAY 0.489362 (-3088 3712);
PAINT MONO (-3088 3712);
FORCEPROP 1 LAST VALUE 0
J 2
(-3275 3700);
DISPLAY 0.489362 (-3275 3700);
PAINT SKYBLUE (-3275 3700);
FORCEPROP 2 LAST ROOM RST_CPU0_PLD_TO_DIMM
J 2
(-3125 3800);
DISPLAY 0.744681 (-3125 3800);
PAINT RED (-3125 3800);
DISPLAY INVISIBLE (-3125 3800);
FORCEPROP 1 LAST PACK_TYPE 0402LF
J 2
(-2975 3625);
DISPLAY 0.489362 (-2975 3625);
PAINT SKYBLUE (-2975 3625);
DISPLAY INVISIBLE (-2975 3625);
FORCEPROP 1 LAST PART_NUMBER CS00002JB38
J 2
(-3050 3750);
DISPLAY 0.489362 (-3050 3750);
PAINT SKYBLUE (-3050 3750);
DISPLAY INVISIBLE (-3050 3750);
FORCEPROP 1 LAST TOLERANCE 5%
J 0
(-3275 3675);
DISPLAY 0.489362 (-3275 3675);
PAINT SKYBLUE (-3275 3675);
DISPLAY INVISIBLE (-3275 3675);
FORCEPROP 1 LAST MATERIAL CHIP
J 2
(-2975 3675);
DISPLAY 0.489362 (-2975 3675);
PAINT SKYBLUE (-2975 3675);
DISPLAY INVISIBLE (-2975 3675);
FORCEPROP 1 LAST WATTAGE 1/16W
J 2
(-3225 3625);
DISPLAY 0.489362 (-3225 3625);
PAINT SKYBLUE (-3225 3625);
DISPLAY INVISIBLE (-3225 3625);
FORCEPROP 1 LAST PATH I1962
J 0
(-3200 3850);
DISPLAY 0.978723 (-3200 3850);
PAINT WHITE (-3200 3850);
DISPLAY INVISIBLE (-3200 3850);
FORCEPROP 2 LAST BOM_COST MEM
J 2
(-3125 3850);
DISPLAY 0.744681 (-3125 3850);
PAINT WHITE (-3125 3850);
DISPLAY INVISIBLE (-3125 3850);
FORCEPROP 2 LAST CDS_LIB pure_quanta
J 0
(-3150 3700);
DISPLAY INVISIBLE (-3150 3700);
FORCEADD OFFPAGE..2
(-2225 3650);
FORCEPROP 2 LAST $XR0 55 
J 0
(-2036 3650);
DISPLAY 0.638298 (-2036 3650);
PAINT MONO (-2036 3650);
FORCEPROP 1 LAST COMMENT_BODY TRUE
J 0
(-2270 3555);
DISPLAY 0.872340 (-2270 3555);
PAINT GREEN (-2270 3555);
DISPLAY INVISIBLE (-2270 3555);
FORCEPROP 1 LAST OFFPAGE TRUE
J 0
(-1900 3525);
DISPLAY 0.872340 (-1900 3525);
PAINT GREEN (-1900 3525);
DISPLAY INVISIBLE (-1900 3525);
FORCEPROP 2 LAST CDS_LIB standard
J 0
(-2225 3650);
DISPLAY INVISIBLE (-2225 3650);
FORCEPROP 2 LAST PATH I1963
J 0
(-2025 3700);
DISPLAY 0.680851 (-2025 3700);
DISPLAY INVISIBLE (-2025 3700);
FORCEADD Q_RES..1
(-3150 3650);
FORCEPROP 1 LAST LOCATION R265
J 0
(-3025 3650);
DISPLAY 0.489362 (-3025 3650);
PAINT SKYBLUE (-3025 3650);
FORCEPROP 0 LAST $SEC 1
J 2
(-3025 3700);
DISPLAY 0.680851 (-3025 3700);
PAINT MONO (-3025 3700);
DISPLAY INVISIBLE (-3025 3700);
FORCEPROP 0 LAST CDS_SEC 1
J 2
(-3025 3700);
DISPLAY 1.021277 (-3025 3700);
DISPLAY INVISIBLE (-3025 3700);
FORCEPROP 1 LASTPIN (-3250 3650) $PN 1
J 0
(-3238 3662);
DISPLAY 0.489362 (-3238 3662);
PAINT MONO (-3238 3662);
FORCEPROP 1 LASTPIN (-3050 3650) $PN 2
J 0
(-3088 3662);
DISPLAY 0.489362 (-3088 3662);
PAINT MONO (-3088 3662);
FORCEPROP 1 LAST VALUE 33
J 2
(-3275 3650);
DISPLAY 0.489362 (-3275 3650);
PAINT SKYBLUE (-3275 3650);
FORCEPROP 2 LAST ROOM RST_CPU0_PLD_TO_DIMM
J 2
(-3125 3750);
DISPLAY 0.744681 (-3125 3750);
PAINT RED (-3125 3750);
DISPLAY INVISIBLE (-3125 3750);
FORCEPROP 1 LAST PACK_TYPE 0402LF
J 2
(-2975 3575);
DISPLAY 0.489362 (-2975 3575);
PAINT SKYBLUE (-2975 3575);
DISPLAY INVISIBLE (-2975 3575);
FORCEPROP 1 LAST PART_NUMBER CS03302JB29
J 2
(-3050 3700);
DISPLAY 0.489362 (-3050 3700);
PAINT SKYBLUE (-3050 3700);
DISPLAY INVISIBLE (-3050 3700);
FORCEPROP 1 LAST TOLERANCE 5%
J 0
(-3275 3625);
DISPLAY 0.489362 (-3275 3625);
PAINT SKYBLUE (-3275 3625);
DISPLAY INVISIBLE (-3275 3625);
FORCEPROP 1 LAST MATERIAL CHIP
J 2
(-2975 3625);
DISPLAY 0.489362 (-2975 3625);
PAINT SKYBLUE (-2975 3625);
DISPLAY INVISIBLE (-2975 3625);
FORCEPROP 1 LAST WATTAGE 1/16W
J 2
(-3225 3575);
DISPLAY 0.489362 (-3225 3575);
PAINT SKYBLUE (-3225 3575);
DISPLAY INVISIBLE (-3225 3575);
FORCEPROP 1 LAST PATH I1964
J 0
(-3200 3800);
DISPLAY 0.978723 (-3200 3800);
PAINT WHITE (-3200 3800);
DISPLAY INVISIBLE (-3200 3800);
FORCEPROP 2 LAST BOM_COST MEM
J 2
(-3125 3800);
DISPLAY 0.744681 (-3125 3800);
PAINT WHITE (-3125 3800);
DISPLAY INVISIBLE (-3125 3800);
FORCEPROP 2 LAST CDS_LIB pure_quanta
J 2
(-3150 3650);
DISPLAY INVISIBLE (-3150 3650);
FORCEADD LCMXO3D9400HC5BG484C..7
(-4750 4825);
FORCEPROP 1 LAST LOCATION U18
J 0
(-5251 6404);
DISPLAY 0.489362 (-5251 6404);
PAINT SKYBLUE (-5251 6404);
FORCEPROP 0 LAST $SEC 7
J 0
(-5225 6525);
DISPLAY 0.680851 (-5225 6525);
PAINT MONO (-5225 6525);
DISPLAY INVISIBLE (-5225 6525);
FORCEPROP 0 LAST CDS_SEC 7
J 0
(-5225 6525);
DISPLAY 0.680851 (-5225 6525);
DISPLAY INVISIBLE (-5225 6525);
FORCEPROP 0 LASTPIN (-5400 6000) $PN C21
J 2
(-5410 6010);
DISPLAY 0.489362 (-5410 6010);
PAINT MONO (-5410 6010);
FORCEPROP 0 LASTPIN (-5400 5950) $PN C22
J 2
(-5410 5960);
DISPLAY 0.489362 (-5410 5960);
PAINT MONO (-5410 5960);
FORCEPROP 0 LASTPIN (-5400 5900) $PN F17
J 2
(-5410 5910);
DISPLAY 0.489362 (-5410 5910);
PAINT MONO (-5410 5910);
FORCEPROP 0 LASTPIN (-5400 5850) $PN G16
J 2
(-5410 5860);
DISPLAY 0.489362 (-5410 5860);
PAINT MONO (-5410 5860);
FORCEPROP 0 LASTPIN (-5400 5800) $PN D22
J 2
(-5410 5810);
DISPLAY 0.489362 (-5410 5810);
PAINT MONO (-5410 5810);
FORCEPROP 0 LASTPIN (-5400 5750) $PN D21
J 2
(-5410 5760);
DISPLAY 0.489362 (-5410 5760);
PAINT MONO (-5410 5760);
FORCEPROP 0 LASTPIN (-5400 5700) $PN D19
J 2
(-5410 5710);
DISPLAY 0.489362 (-5410 5710);
PAINT MONO (-5410 5710);
FORCEPROP 0 LASTPIN (-5400 5650) $PN D20
J 2
(-5410 5660);
DISPLAY 0.489362 (-5410 5660);
PAINT MONO (-5410 5660);
FORCEPROP 0 LASTPIN (-5400 5600) $PN E22
J 2
(-5410 5610);
DISPLAY 0.489362 (-5410 5610);
PAINT MONO (-5410 5610);
FORCEPROP 0 LASTPIN (-5400 5550) $PN E21
J 2
(-5410 5560);
DISPLAY 0.489362 (-5410 5560);
PAINT MONO (-5410 5560);
FORCEPROP 0 LASTPIN (-5400 5500) $PN E19
J 2
(-5410 5510);
DISPLAY 0.489362 (-5410 5510);
PAINT MONO (-5410 5510);
FORCEPROP 0 LASTPIN (-5400 5450) $PN E20
J 2
(-5410 5460);
DISPLAY 0.489362 (-5410 5460);
PAINT MONO (-5410 5460);
FORCEPROP 0 LASTPIN (-5400 5400) $PN F22
J 2
(-5410 5410);
DISPLAY 0.489362 (-5410 5410);
PAINT MONO (-5410 5410);
FORCEPROP 0 LASTPIN (-5400 5350) $PN G22
J 2
(-5410 5360);
DISPLAY 0.489362 (-5410 5360);
PAINT MONO (-5410 5360);
FORCEPROP 0 LASTPIN (-5400 5300) $PN F18
J 2
(-5410 5310);
DISPLAY 0.489362 (-5410 5310);
PAINT MONO (-5410 5310);
FORCEPROP 0 LASTPIN (-5400 5250) $PN F19
J 2
(-5410 5260);
DISPLAY 0.489362 (-5410 5260);
PAINT MONO (-5410 5260);
FORCEPROP 0 LASTPIN (-5400 5200) $PN G21
J 2
(-5410 5210);
DISPLAY 0.489362 (-5410 5210);
PAINT MONO (-5410 5210);
FORCEPROP 0 LASTPIN (-5400 5150) $PN G20
J 2
(-5410 5160);
DISPLAY 0.489362 (-5410 5160);
PAINT MONO (-5410 5160);
FORCEPROP 0 LASTPIN (-5400 5100) $PN G19
J 2
(-5410 5110);
DISPLAY 0.489362 (-5410 5110);
PAINT MONO (-5410 5110);
FORCEPROP 0 LASTPIN (-5400 5050) $PN G18
J 2
(-5410 5060);
DISPLAY 0.489362 (-5410 5060);
PAINT MONO (-5410 5060);
FORCEPROP 0 LASTPIN (-5400 5000) $PN H22
J 2
(-5410 5010);
DISPLAY 0.489362 (-5410 5010);
PAINT MONO (-5410 5010);
FORCEPROP 0 LASTPIN (-5400 4950) $PN H21
J 2
(-5410 4960);
DISPLAY 0.489362 (-5410 4960);
PAINT MONO (-5410 4960);
FORCEPROP 0 LASTPIN (-5400 4900) $PN G17
J 2
(-5410 4910);
DISPLAY 0.489362 (-5410 4910);
PAINT MONO (-5410 4910);
FORCEPROP 0 LASTPIN (-5400 4850) $PN H20
J 2
(-5410 4860);
DISPLAY 0.489362 (-5410 4860);
PAINT MONO (-5410 4860);
FORCEPROP 0 LASTPIN (-5400 4800) $PN H19
J 2
(-5410 4810);
DISPLAY 0.489362 (-5410 4810);
PAINT MONO (-5410 4810);
FORCEPROP 0 LASTPIN (-5400 4750) $PN H18
J 2
(-5410 4760);
DISPLAY 0.489362 (-5410 4760);
PAINT MONO (-5410 4760);
FORCEPROP 0 LASTPIN (-5400 4700) $PN H17
J 2
(-5410 4710);
DISPLAY 0.489362 (-5410 4710);
PAINT MONO (-5410 4710);
FORCEPROP 0 LASTPIN (-5400 4650) $PN H16
J 2
(-5410 4660);
DISPLAY 0.489362 (-5410 4660);
PAINT MONO (-5410 4660);
FORCEPROP 0 LASTPIN (-5400 4600) $PN J16
J 2
(-5410 4610);
DISPLAY 0.489362 (-5410 4610);
PAINT MONO (-5410 4610);
FORCEPROP 0 LASTPIN (-5400 4550) $PN J17
J 2
(-5410 4560);
DISPLAY 0.489362 (-5410 4560);
PAINT MONO (-5410 4560);
FORCEPROP 0 LASTPIN (-5400 4500) $PN J18
J 2
(-5410 4510);
DISPLAY 0.489362 (-5410 4510);
PAINT MONO (-5410 4510);
FORCEPROP 0 LASTPIN (-5400 4450) $PN J19
J 2
(-5410 4460);
DISPLAY 0.489362 (-5410 4460);
PAINT MONO (-5410 4460);
FORCEPROP 0 LASTPIN (-5400 4400) $PN J21
J 2
(-5410 4410);
DISPLAY 0.489362 (-5410 4410);
PAINT MONO (-5410 4410);
FORCEPROP 0 LASTPIN (-5400 4350) $PN J22
J 2
(-5410 4360);
DISPLAY 0.489362 (-5410 4360);
PAINT MONO (-5410 4360);
FORCEPROP 0 LASTPIN (-5400 4300) $PN J20
J 2
(-5410 4310);
DISPLAY 0.489362 (-5410 4310);
PAINT MONO (-5410 4310);
FORCEPROP 0 LASTPIN (-5400 4250) $PN K20
J 2
(-5410 4260);
DISPLAY 0.489362 (-5410 4260);
PAINT MONO (-5410 4260);
FORCEPROP 0 LASTPIN (-5400 4200) $PN K19
J 2
(-5410 4210);
DISPLAY 0.489362 (-5410 4210);
PAINT MONO (-5410 4210);
FORCEPROP 0 LASTPIN (-5400 4150) $PN K18
J 2
(-5410 4160);
DISPLAY 0.489362 (-5410 4160);
PAINT MONO (-5410 4160);
FORCEPROP 0 LASTPIN (-5400 4100) $PN K17
J 2
(-5410 4110);
DISPLAY 0.489362 (-5410 4110);
PAINT MONO (-5410 4110);
FORCEPROP 0 LASTPIN (-5400 4050) $PN K16
J 2
(-5410 4060);
DISPLAY 0.489362 (-5410 4060);
PAINT MONO (-5410 4060);
FORCEPROP 0 LASTPIN (-5400 4000) $PN L17
J 2
(-5410 4010);
DISPLAY 0.489362 (-5410 4010);
PAINT MONO (-5410 4010);
FORCEPROP 0 LASTPIN (-5400 3950) $PN L16
J 2
(-5410 3960);
DISPLAY 0.489362 (-5410 3960);
PAINT MONO (-5410 3960);
FORCEPROP 0 LASTPIN (-5400 3900) $PN L19
J 2
(-5410 3910);
DISPLAY 0.489362 (-5410 3910);
PAINT MONO (-5410 3910);
FORCEPROP 0 LASTPIN (-5400 3850) $PN L20
J 2
(-5410 3860);
DISPLAY 0.489362 (-5410 3860);
PAINT MONO (-5410 3860);
FORCEPROP 0 LASTPIN (-5400 3800) $PN K22
J 2
(-5410 3810);
DISPLAY 0.489362 (-5410 3810);
PAINT MONO (-5410 3810);
FORCEPROP 0 LASTPIN (-5400 3750) $PN L21
J 2
(-5410 3760);
DISPLAY 0.489362 (-5410 3760);
PAINT MONO (-5410 3760);
FORCEPROP 0 LASTPIN (-5400 3700) $PN L22
J 2
(-5410 3710);
DISPLAY 0.489362 (-5410 3710);
PAINT MONO (-5410 3710);
FORCEPROP 0 LASTPIN (-5400 3650) $PN M17
J 2
(-5410 3660);
DISPLAY 0.489362 (-5410 3660);
PAINT MONO (-5410 3660);
FORCEPROP 0 LASTPIN (-4100 6000) $PN M22
J 0
(-4090 6010);
DISPLAY 0.489362 (-4090 6010);
PAINT MONO (-4090 6010);
FORCEPROP 0 LASTPIN (-4100 5950) $PN M21
J 0
(-4090 5960);
DISPLAY 0.489362 (-4090 5960);
PAINT MONO (-4090 5960);
FORCEPROP 0 LASTPIN (-4100 5900) $PN M20
J 0
(-4090 5910);
DISPLAY 0.489362 (-4090 5910);
PAINT MONO (-4090 5910);
FORCEPROP 0 LASTPIN (-4100 5850) $PN M19
J 0
(-4090 5860);
DISPLAY 0.489362 (-4090 5860);
PAINT MONO (-4090 5860);
FORCEPROP 0 LASTPIN (-4100 5800) $PN M16
J 0
(-4090 5810);
DISPLAY 0.489362 (-4090 5810);
PAINT MONO (-4090 5810);
FORCEPROP 0 LASTPIN (-4100 5750) $PN N16
J 0
(-4090 5760);
DISPLAY 0.489362 (-4090 5760);
PAINT MONO (-4090 5760);
FORCEPROP 0 LASTPIN (-4100 5700) $PN N17
J 0
(-4090 5710);
DISPLAY 0.489362 (-4090 5710);
PAINT MONO (-4090 5710);
FORCEPROP 0 LASTPIN (-4100 5650) $PN N18
J 0
(-4090 5660);
DISPLAY 0.489362 (-4090 5660);
PAINT MONO (-4090 5660);
FORCEPROP 0 LASTPIN (-4100 5600) $PN N22
J 0
(-4090 5610);
DISPLAY 0.489362 (-4090 5610);
PAINT MONO (-4090 5610);
FORCEPROP 0 LASTPIN (-4100 5550) $PN P21
J 0
(-4090 5560);
DISPLAY 0.489362 (-4090 5560);
PAINT MONO (-4090 5560);
FORCEPROP 0 LASTPIN (-4100 5500) $PN N20
J 0
(-4090 5510);
DISPLAY 0.489362 (-4090 5510);
PAINT MONO (-4090 5510);
FORCEPROP 0 LASTPIN (-4100 5450) $PN N19
J 0
(-4090 5460);
DISPLAY 0.489362 (-4090 5460);
PAINT MONO (-4090 5460);
FORCEPROP 0 LASTPIN (-4100 5400) $PN R22
J 0
(-4090 5410);
DISPLAY 0.489362 (-4090 5410);
PAINT MONO (-4090 5410);
FORCEPROP 0 LASTPIN (-4100 5350) $PN R21
J 0
(-4090 5360);
DISPLAY 0.489362 (-4090 5360);
PAINT MONO (-4090 5360);
FORCEPROP 0 LASTPIN (-4100 5300) $PN P22
J 0
(-4090 5310);
DISPLAY 0.489362 (-4090 5310);
PAINT MONO (-4090 5310);
FORCEPROP 0 LASTPIN (-4100 5250) $PN P20
J 0
(-4090 5260);
DISPLAY 0.489362 (-4090 5260);
PAINT MONO (-4090 5260);
FORCEPROP 0 LASTPIN (-4100 5200) $PN T22
J 0
(-4090 5210);
DISPLAY 0.489362 (-4090 5210);
PAINT MONO (-4090 5210);
FORCEPROP 0 LASTPIN (-4100 5150) $PN T21
J 0
(-4090 5160);
DISPLAY 0.489362 (-4090 5160);
PAINT MONO (-4090 5160);
FORCEPROP 0 LASTPIN (-4100 5100) $PN P19
J 0
(-4090 5110);
DISPLAY 0.489362 (-4090 5110);
PAINT MONO (-4090 5110);
FORCEPROP 0 LASTPIN (-4100 5050) $PN P18
J 0
(-4090 5060);
DISPLAY 0.489362 (-4090 5060);
PAINT MONO (-4090 5060);
FORCEPROP 0 LASTPIN (-4100 5000) $PN P17
J 0
(-4090 5010);
DISPLAY 0.489362 (-4090 5010);
PAINT MONO (-4090 5010);
FORCEPROP 0 LASTPIN (-4100 4950) $PN P16
J 0
(-4090 4960);
DISPLAY 0.489362 (-4090 4960);
PAINT MONO (-4090 4960);
FORCEPROP 0 LASTPIN (-4100 4900) $PN U22
J 0
(-4090 4910);
DISPLAY 0.489362 (-4090 4910);
PAINT MONO (-4090 4910);
FORCEPROP 0 LASTPIN (-4100 4850) $PN U21
J 0
(-4090 4860);
DISPLAY 0.489362 (-4090 4860);
PAINT MONO (-4090 4860);
FORCEPROP 0 LASTPIN (-4100 4800) $PN V22
J 0
(-4090 4810);
DISPLAY 0.489362 (-4090 4810);
PAINT MONO (-4090 4810);
FORCEPROP 0 LASTPIN (-4100 4750) $PN W22
J 0
(-4090 4760);
DISPLAY 0.489362 (-4090 4760);
PAINT MONO (-4090 4760);
FORCEPROP 0 LASTPIN (-4100 4700) $PN R20
J 0
(-4090 4710);
DISPLAY 0.489362 (-4090 4710);
PAINT MONO (-4090 4710);
FORCEPROP 0 LASTPIN (-4100 4650) $PN R19
J 0
(-4090 4660);
DISPLAY 0.489362 (-4090 4660);
PAINT MONO (-4090 4660);
FORCEPROP 0 LASTPIN (-4100 4550) $PN R18
J 0
(-4090 4560);
DISPLAY 0.489362 (-4090 4560);
PAINT MONO (-4090 4560);
FORCEPROP 0 LASTPIN (-4100 4500) $PN R17
J 0
(-4090 4510);
DISPLAY 0.489362 (-4090 4510);
PAINT MONO (-4090 4510);
FORCEPROP 0 LASTPIN (-4100 4450) $PN R16
J 0
(-4090 4460);
DISPLAY 0.489362 (-4090 4460);
PAINT MONO (-4090 4460);
FORCEPROP 0 LASTPIN (-4100 4400) $PN T20
J 0
(-4090 4410);
DISPLAY 0.489362 (-4090 4410);
PAINT MONO (-4090 4410);
FORCEPROP 0 LASTPIN (-4100 4350) $PN T19
J 0
(-4090 4360);
DISPLAY 0.489362 (-4090 4360);
PAINT MONO (-4090 4360);
FORCEPROP 0 LASTPIN (-4100 4300) $PN T18
J 0
(-4090 4310);
DISPLAY 0.489362 (-4090 4310);
PAINT MONO (-4090 4310);
FORCEPROP 0 LASTPIN (-4100 4250) $PN T17
J 0
(-4090 4260);
DISPLAY 0.489362 (-4090 4260);
PAINT MONO (-4090 4260);
FORCEPROP 0 LASTPIN (-4100 4200) $PN U20
J 0
(-4090 4210);
DISPLAY 0.489362 (-4090 4210);
PAINT MONO (-4090 4210);
FORCEPROP 0 LASTPIN (-4100 4150) $PN Y22
J 0
(-4090 4160);
DISPLAY 0.489362 (-4090 4160);
PAINT MONO (-4090 4160);
FORCEPROP 0 LASTPIN (-4100 4100) $PN W21
J 0
(-4090 4110);
DISPLAY 0.489362 (-4090 4110);
PAINT MONO (-4090 4110);
FORCEPROP 0 LASTPIN (-4100 4050) $PN U19
J 0
(-4090 4060);
DISPLAY 0.489362 (-4090 4060);
PAINT MONO (-4090 4060);
FORCEPROP 0 LASTPIN (-4100 4000) $PN U18
J 0
(-4090 4010);
DISPLAY 0.489362 (-4090 4010);
PAINT MONO (-4090 4010);
FORCEPROP 0 LASTPIN (-4100 3950) $PN AA22
J 0
(-4090 3960);
DISPLAY 0.489362 (-4090 3960);
PAINT MONO (-4090 3960);
FORCEPROP 0 LASTPIN (-4100 3900) $PN Y21
J 0
(-4090 3910);
DISPLAY 0.489362 (-4090 3910);
PAINT MONO (-4090 3910);
FORCEPROP 0 LASTPIN (-4100 3850) $PN U17
J 0
(-4090 3860);
DISPLAY 0.489362 (-4090 3860);
PAINT MONO (-4090 3860);
FORCEPROP 0 LASTPIN (-4100 3800) $PN V19
J 0
(-4090 3810);
DISPLAY 0.489362 (-4090 3810);
PAINT MONO (-4090 3810);
FORCEPROP 0 LASTPIN (-4100 3750) $PN V18
J 0
(-4090 3760);
DISPLAY 0.489362 (-4090 3760);
PAINT MONO (-4090 3760);
FORCEPROP 0 LASTPIN (-4100 3700) $PN W20
J 0
(-4090 3710);
DISPLAY 0.489362 (-4090 3710);
PAINT MONO (-4090 3710);
FORCEPROP 0 LASTPIN (-4100 3650) $PN W19
J 0
(-4090 3660);
DISPLAY 0.489362 (-4090 3660);
PAINT MONO (-4090 3660);
FORCEPROP 0 LASTPIN (-4100 3600) $PN Y20
J 0
(-4090 3610);
DISPLAY 0.489362 (-4090 3610);
PAINT MONO (-4090 3610);
FORCEPROP 1 LAST PART_NUMBER AJ094000T05
J 0
(-5251 6257);
DISPLAY 0.489362 (-5251 6257);
PAINT SKYBLUE (-5251 6257);
FORCEPROP 2 LAST VALUE LCMXO3D-9400HC-5BG484C
J 0
(-5245 6445);
DISPLAY 0.489362 (-5245 6445);
PAINT SKYBLUE (-5245 6445);
FORCEPROP 1 LAST MATERIAL IC
J 0
(-5251 6130);
DISPLAY 0.489362 (-5251 6130);
PAINT SKYBLUE (-5251 6130);
FORCEPROP 2 LAST PART_TYPE SMLF
J 0
(-5245 6490);
DISPLAY 0.680851 (-5245 6490);
FORCEPROP 1 LAST PATH I1965
J 0
(-4750 4825);
DISPLAY 0.723404 (-4750 4825);
PAINT GREEN (-4750 4825);
DISPLAY INVISIBLE (-4750 4825);
FORCEPROP 2 LAST CDS_LIB pure_quanta
J 0
(-4750 4825);
DISPLAY INVISIBLE (-4750 4825);
FORCEPROP 1 LAST CDS_LMAN_SYM_OUTLINE -500,1275,500,-1275
J 0
(-4750 4825);
DISPLAY 0.468085 (-4750 4825);
PAINT GREEN (-4750 4825);
DISPLAY INVISIBLE (-4750 4825);
FORCEPROP 1 LAST NEEDS_NO_SIZE TRUE
J 0
(-4750 4825);
DISPLAY 0.723404 (-4750 4825);
PAINT GREEN (-4750 4825);
DISPLAY INVISIBLE (-4750 4825);
FORCEADD Q_RES..1
(-6350 4600);
FORCEPROP 1 LAST LOCATION R219
J 0
(-6225 4600);
DISPLAY 0.489362 (-6225 4600);
PAINT SKYBLUE (-6225 4600);
FORCEPROP 0 LAST $SEC 1
J 2
(-6225 4650);
DISPLAY 0.680851 (-6225 4650);
PAINT MONO (-6225 4650);
DISPLAY INVISIBLE (-6225 4650);
FORCEPROP 0 LAST CDS_SEC 1
J 2
(-6225 4650);
DISPLAY 1.021277 (-6225 4650);
DISPLAY INVISIBLE (-6225 4650);
FORCEPROP 1 LASTPIN (-6450 4600) $PN 1
J 0
(-6438 4612);
DISPLAY 0.489362 (-6438 4612);
PAINT MONO (-6438 4612);
FORCEPROP 1 LASTPIN (-6250 4600) $PN 2
J 0
(-6288 4612);
DISPLAY 0.489362 (-6288 4612);
PAINT MONO (-6288 4612);
FORCEPROP 1 LAST VALUE 33
J 2
(-6475 4600);
DISPLAY 0.489362 (-6475 4600);
PAINT SKYBLUE (-6475 4600);
FORCEPROP 2 LAST ROOM RST_CPU0_PLD_TO_DIMM
J 2
(-6325 4700);
DISPLAY 0.744681 (-6325 4700);
PAINT RED (-6325 4700);
DISPLAY INVISIBLE (-6325 4700);
FORCEPROP 1 LAST PACK_TYPE 0402LF
J 2
(-6175 4525);
DISPLAY 0.489362 (-6175 4525);
PAINT SKYBLUE (-6175 4525);
DISPLAY INVISIBLE (-6175 4525);
FORCEPROP 1 LAST PART_NUMBER CS03302JB29
J 2
(-6250 4650);
DISPLAY 0.489362 (-6250 4650);
PAINT SKYBLUE (-6250 4650);
DISPLAY INVISIBLE (-6250 4650);
FORCEPROP 1 LAST TOLERANCE 5%
J 0
(-6475 4575);
DISPLAY 0.489362 (-6475 4575);
PAINT SKYBLUE (-6475 4575);
DISPLAY INVISIBLE (-6475 4575);
FORCEPROP 1 LAST MATERIAL CHIP
J 2
(-6175 4575);
DISPLAY 0.489362 (-6175 4575);
PAINT SKYBLUE (-6175 4575);
DISPLAY INVISIBLE (-6175 4575);
FORCEPROP 1 LAST WATTAGE 1/16W
J 2
(-6425 4525);
DISPLAY 0.489362 (-6425 4525);
PAINT SKYBLUE (-6425 4525);
DISPLAY INVISIBLE (-6425 4525);
FORCEPROP 1 LAST PATH I1966
J 0
(-6400 4750);
DISPLAY 0.978723 (-6400 4750);
PAINT WHITE (-6400 4750);
DISPLAY INVISIBLE (-6400 4750);
FORCEPROP 2 LAST BOM_COST MEM
J 2
(-6325 4750);
DISPLAY 0.744681 (-6325 4750);
PAINT WHITE (-6325 4750);
DISPLAY INVISIBLE (-6325 4750);
FORCEPROP 2 LAST CDS_LIB pure_quanta
J 2
(-6350 4600);
DISPLAY INVISIBLE (-6350 4600);
FORCEADD Q_RES..1
(-6350 4500);
FORCEPROP 1 LAST LOCATION R203
J 0
(-6225 4500);
DISPLAY 0.489362 (-6225 4500);
PAINT SKYBLUE (-6225 4500);
FORCEPROP 0 LAST $SEC 1
J 2
(-6225 4550);
DISPLAY 0.680851 (-6225 4550);
PAINT MONO (-6225 4550);
DISPLAY INVISIBLE (-6225 4550);
FORCEPROP 0 LAST CDS_SEC 1
J 2
(-6225 4550);
DISPLAY 1.021277 (-6225 4550);
DISPLAY INVISIBLE (-6225 4550);
FORCEPROP 1 LASTPIN (-6450 4500) $PN 1
J 0
(-6438 4512);
DISPLAY 0.489362 (-6438 4512);
PAINT MONO (-6438 4512);
FORCEPROP 1 LASTPIN (-6250 4500) $PN 2
J 0
(-6288 4512);
DISPLAY 0.489362 (-6288 4512);
PAINT MONO (-6288 4512);
FORCEPROP 1 LAST VALUE 0
J 2
(-6475 4500);
DISPLAY 0.489362 (-6475 4500);
PAINT SKYBLUE (-6475 4500);
FORCEPROP 2 LAST ROOM RST_CPU0_PLD_TO_DIMM
J 2
(-6325 4600);
DISPLAY 0.744681 (-6325 4600);
PAINT RED (-6325 4600);
DISPLAY INVISIBLE (-6325 4600);
FORCEPROP 1 LAST PACK_TYPE 0402LF
J 2
(-6175 4425);
DISPLAY 0.489362 (-6175 4425);
PAINT SKYBLUE (-6175 4425);
DISPLAY INVISIBLE (-6175 4425);
FORCEPROP 1 LAST PART_NUMBER CS00002JB38
J 2
(-6250 4550);
DISPLAY 0.489362 (-6250 4550);
PAINT SKYBLUE (-6250 4550);
DISPLAY INVISIBLE (-6250 4550);
FORCEPROP 1 LAST TOLERANCE 5%
J 0
(-6475 4475);
DISPLAY 0.489362 (-6475 4475);
PAINT SKYBLUE (-6475 4475);
DISPLAY INVISIBLE (-6475 4475);
FORCEPROP 1 LAST MATERIAL CHIP
J 2
(-6175 4475);
DISPLAY 0.489362 (-6175 4475);
PAINT SKYBLUE (-6175 4475);
DISPLAY INVISIBLE (-6175 4475);
FORCEPROP 1 LAST WATTAGE 1/16W
J 2
(-6425 4425);
DISPLAY 0.489362 (-6425 4425);
PAINT SKYBLUE (-6425 4425);
DISPLAY INVISIBLE (-6425 4425);
FORCEPROP 1 LAST PATH I1967
J 0
(-6400 4650);
DISPLAY 0.978723 (-6400 4650);
PAINT WHITE (-6400 4650);
DISPLAY INVISIBLE (-6400 4650);
FORCEPROP 2 LAST CDS_LIB pure_quanta
J 2
(-6350 4500);
DISPLAY INVISIBLE (-6350 4500);
FORCEPROP 2 LAST BOM_COST MEM
J 2
(-6325 4650);
DISPLAY 0.744681 (-6325 4650);
PAINT WHITE (-6325 4650);
DISPLAY INVISIBLE (-6325 4650);
FORCEADD Q_RES..1
(-6350 4550);
FORCEPROP 1 LAST LOCATION R371
J 0
(-6225 4550);
DISPLAY 0.489362 (-6225 4550);
PAINT SKYBLUE (-6225 4550);
FORCEPROP 0 LAST $SEC 1
J 0
(-6225 4600);
DISPLAY 0.680851 (-6225 4600);
PAINT MONO (-6225 4600);
DISPLAY INVISIBLE (-6225 4600);
FORCEPROP 0 LAST CDS_SEC 1
J 0
(-6225 4600);
DISPLAY 0.680851 (-6225 4600);
DISPLAY INVISIBLE (-6225 4600);
FORCEPROP 1 LASTPIN (-6450 4550) $PN 1
J 0
(-6438 4562);
DISPLAY 0.489362 (-6438 4562);
PAINT MONO (-6438 4562);
FORCEPROP 1 LASTPIN (-6250 4550) $PN 2
J 0
(-6288 4562);
DISPLAY 0.489362 (-6288 4562);
PAINT MONO (-6288 4562);
FORCEPROP 1 LAST VALUE 33
J 2
(-6475 4550);
DISPLAY 0.489362 (-6475 4550);
PAINT SKYBLUE (-6475 4550);
FORCEPROP 2 LAST ROOM RST_CPU0_PLD_TO_DIMM
J 2
(-6325 4650);
DISPLAY 0.744681 (-6325 4650);
PAINT RED (-6325 4650);
DISPLAY INVISIBLE (-6325 4650);
FORCEPROP 1 LAST PACK_TYPE 0402LF
J 2
(-6175 4475);
DISPLAY 0.489362 (-6175 4475);
PAINT SKYBLUE (-6175 4475);
DISPLAY INVISIBLE (-6175 4475);
FORCEPROP 1 LAST PART_NUMBER CS03302JB29
J 2
(-6250 4600);
DISPLAY 0.489362 (-6250 4600);
PAINT SKYBLUE (-6250 4600);
DISPLAY INVISIBLE (-6250 4600);
FORCEPROP 1 LAST TOLERANCE 5%
J 0
(-6475 4525);
DISPLAY 0.489362 (-6475 4525);
PAINT SKYBLUE (-6475 4525);
DISPLAY INVISIBLE (-6475 4525);
FORCEPROP 1 LAST MATERIAL CHIP
J 2
(-6175 4525);
DISPLAY 0.489362 (-6175 4525);
PAINT SKYBLUE (-6175 4525);
DISPLAY INVISIBLE (-6175 4525);
FORCEPROP 1 LAST WATTAGE 1/16W
J 2
(-6425 4475);
DISPLAY 0.489362 (-6425 4475);
PAINT SKYBLUE (-6425 4475);
DISPLAY INVISIBLE (-6425 4475);
FORCEPROP 1 LAST PATH I1968
J 0
(-6400 4700);
DISPLAY 0.978723 (-6400 4700);
PAINT WHITE (-6400 4700);
DISPLAY INVISIBLE (-6400 4700);
FORCEPROP 2 LAST BOM_COST MEM
J 2
(-6325 4700);
DISPLAY 0.744681 (-6325 4700);
PAINT WHITE (-6325 4700);
DISPLAY INVISIBLE (-6325 4700);
FORCEPROP 2 LAST CDS_LIB pure_quanta
J 0
(-6350 4550);
DISPLAY INVISIBLE (-6350 4550);
FORCEADD Q_RES..1
(-6350 4450);
FORCEPROP 1 LAST LOCATION R1278
J 0
(-6225 4450);
DISPLAY 0.489362 (-6225 4450);
PAINT SKYBLUE (-6225 4450);
FORCEPROP 0 LAST $SEC 1
J 0
(-6225 4500);
DISPLAY 0.680851 (-6225 4500);
PAINT MONO (-6225 4500);
DISPLAY INVISIBLE (-6225 4500);
FORCEPROP 0 LAST CDS_SEC 1
J 0
(-6225 4500);
DISPLAY 0.680851 (-6225 4500);
DISPLAY INVISIBLE (-6225 4500);
FORCEPROP 1 LASTPIN (-6450 4450) $PN 1
J 0
(-6438 4462);
DISPLAY 0.489362 (-6438 4462);
PAINT MONO (-6438 4462);
FORCEPROP 1 LASTPIN (-6250 4450) $PN 2
J 0
(-6288 4462);
DISPLAY 0.489362 (-6288 4462);
PAINT MONO (-6288 4462);
FORCEPROP 1 LAST VALUE 33
J 2
(-6475 4450);
DISPLAY 0.489362 (-6475 4450);
PAINT SKYBLUE (-6475 4450);
FORCEPROP 2 LAST ROOM RST_CPU0_PLD_TO_DIMM
J 2
(-6325 4550);
DISPLAY 0.744681 (-6325 4550);
PAINT RED (-6325 4550);
DISPLAY INVISIBLE (-6325 4550);
FORCEPROP 1 LAST PACK_TYPE 0402LF
J 2
(-6175 4375);
DISPLAY 0.489362 (-6175 4375);
PAINT SKYBLUE (-6175 4375);
DISPLAY INVISIBLE (-6175 4375);
FORCEPROP 1 LAST PART_NUMBER CS03302JB29
J 2
(-6250 4500);
DISPLAY 0.489362 (-6250 4500);
PAINT SKYBLUE (-6250 4500);
DISPLAY INVISIBLE (-6250 4500);
FORCEPROP 1 LAST TOLERANCE 5%
J 0
(-6475 4425);
DISPLAY 0.489362 (-6475 4425);
PAINT SKYBLUE (-6475 4425);
DISPLAY INVISIBLE (-6475 4425);
FORCEPROP 1 LAST MATERIAL CHIP
J 2
(-6175 4425);
DISPLAY 0.489362 (-6175 4425);
PAINT SKYBLUE (-6175 4425);
DISPLAY INVISIBLE (-6175 4425);
FORCEPROP 1 LAST WATTAGE 1/16W
J 2
(-6425 4375);
DISPLAY 0.489362 (-6425 4375);
PAINT SKYBLUE (-6425 4375);
DISPLAY INVISIBLE (-6425 4375);
FORCEPROP 1 LAST PATH I1969
J 0
(-6400 4600);
DISPLAY 0.978723 (-6400 4600);
PAINT WHITE (-6400 4600);
DISPLAY INVISIBLE (-6400 4600);
FORCEPROP 2 LAST BOM_COST MEM
J 2
(-6325 4600);
DISPLAY 0.744681 (-6325 4600);
PAINT WHITE (-6325 4600);
DISPLAY INVISIBLE (-6325 4600);
FORCEPROP 2 LAST CDS_LIB pure_quanta
J 0
(-6350 4450);
DISPLAY INVISIBLE (-6350 4450);
FORCEADD Q_RES..1
(-6350 4350);
FORCEPROP 1 LAST LOCATION R215
J 0
(-6225 4350);
DISPLAY 0.489362 (-6225 4350);
PAINT SKYBLUE (-6225 4350);
FORCEPROP 0 LAST $SEC 1
J 2
(-6225 4400);
DISPLAY 0.680851 (-6225 4400);
PAINT MONO (-6225 4400);
DISPLAY INVISIBLE (-6225 4400);
FORCEPROP 0 LAST CDS_SEC 1
J 2
(-6225 4400);
DISPLAY 1.021277 (-6225 4400);
DISPLAY INVISIBLE (-6225 4400);
FORCEPROP 1 LASTPIN (-6450 4350) $PN 1
J 0
(-6438 4362);
DISPLAY 0.489362 (-6438 4362);
PAINT MONO (-6438 4362);
FORCEPROP 1 LASTPIN (-6250 4350) $PN 2
J 0
(-6288 4362);
DISPLAY 0.489362 (-6288 4362);
PAINT MONO (-6288 4362);
FORCEPROP 1 LAST VALUE 33
J 2
(-6475 4350);
DISPLAY 0.489362 (-6475 4350);
PAINT SKYBLUE (-6475 4350);
FORCEPROP 2 LAST ROOM RST_CPU0_PLD_TO_DIMM
J 2
(-6325 4450);
DISPLAY 0.744681 (-6325 4450);
PAINT RED (-6325 4450);
DISPLAY INVISIBLE (-6325 4450);
FORCEPROP 1 LAST PACK_TYPE 0402LF
J 2
(-6175 4275);
DISPLAY 0.489362 (-6175 4275);
PAINT SKYBLUE (-6175 4275);
DISPLAY INVISIBLE (-6175 4275);
FORCEPROP 1 LAST PART_NUMBER CS03302JB29
J 2
(-6250 4400);
DISPLAY 0.489362 (-6250 4400);
PAINT SKYBLUE (-6250 4400);
DISPLAY INVISIBLE (-6250 4400);
FORCEPROP 1 LAST TOLERANCE 5%
J 0
(-6475 4325);
DISPLAY 0.489362 (-6475 4325);
PAINT SKYBLUE (-6475 4325);
DISPLAY INVISIBLE (-6475 4325);
FORCEPROP 1 LAST MATERIAL CHIP
J 2
(-6175 4325);
DISPLAY 0.489362 (-6175 4325);
PAINT SKYBLUE (-6175 4325);
DISPLAY INVISIBLE (-6175 4325);
FORCEPROP 1 LAST WATTAGE 1/16W
J 2
(-6425 4275);
DISPLAY 0.489362 (-6425 4275);
PAINT SKYBLUE (-6425 4275);
DISPLAY INVISIBLE (-6425 4275);
FORCEPROP 1 LAST PATH I1970
J 0
(-6400 4500);
DISPLAY 0.978723 (-6400 4500);
PAINT WHITE (-6400 4500);
DISPLAY INVISIBLE (-6400 4500);
FORCEPROP 2 LAST BOM_COST MEM
J 2
(-6325 4500);
DISPLAY 0.744681 (-6325 4500);
PAINT WHITE (-6325 4500);
DISPLAY INVISIBLE (-6325 4500);
FORCEPROP 2 LAST CDS_LIB pure_quanta
J 2
(-6350 4350);
DISPLAY INVISIBLE (-6350 4350);
FORCEADD Q_RES..1
(-6350 4300);
FORCEPROP 1 LAST LOCATION R1279
J 0
(-6225 4300);
DISPLAY 0.489362 (-6225 4300);
PAINT SKYBLUE (-6225 4300);
FORCEPROP 0 LAST $SEC 1
J 0
(-6225 4350);
DISPLAY 0.680851 (-6225 4350);
PAINT MONO (-6225 4350);
DISPLAY INVISIBLE (-6225 4350);
FORCEPROP 0 LAST CDS_SEC 1
J 0
(-6225 4350);
DISPLAY 0.680851 (-6225 4350);
DISPLAY INVISIBLE (-6225 4350);
FORCEPROP 1 LASTPIN (-6450 4300) $PN 1
J 0
(-6438 4312);
DISPLAY 0.489362 (-6438 4312);
PAINT MONO (-6438 4312);
FORCEPROP 1 LASTPIN (-6250 4300) $PN 2
J 0
(-6288 4312);
DISPLAY 0.489362 (-6288 4312);
PAINT MONO (-6288 4312);
FORCEPROP 1 LAST VALUE 33
J 2
(-6475 4300);
DISPLAY 0.489362 (-6475 4300);
PAINT SKYBLUE (-6475 4300);
FORCEPROP 2 LAST ROOM RST_CPU0_PLD_TO_DIMM
J 2
(-6325 4400);
DISPLAY 0.744681 (-6325 4400);
PAINT RED (-6325 4400);
DISPLAY INVISIBLE (-6325 4400);
FORCEPROP 1 LAST PACK_TYPE 0402LF
J 2
(-6175 4225);
DISPLAY 0.489362 (-6175 4225);
PAINT SKYBLUE (-6175 4225);
DISPLAY INVISIBLE (-6175 4225);
FORCEPROP 1 LAST PART_NUMBER CS03302JB29
J 2
(-6250 4350);
DISPLAY 0.489362 (-6250 4350);
PAINT SKYBLUE (-6250 4350);
DISPLAY INVISIBLE (-6250 4350);
FORCEPROP 1 LAST TOLERANCE 5%
J 0
(-6475 4275);
DISPLAY 0.489362 (-6475 4275);
PAINT SKYBLUE (-6475 4275);
DISPLAY INVISIBLE (-6475 4275);
FORCEPROP 1 LAST MATERIAL CHIP
J 2
(-6175 4275);
DISPLAY 0.489362 (-6175 4275);
PAINT SKYBLUE (-6175 4275);
DISPLAY INVISIBLE (-6175 4275);
FORCEPROP 1 LAST WATTAGE 1/16W
J 2
(-6425 4225);
DISPLAY 0.489362 (-6425 4225);
PAINT SKYBLUE (-6425 4225);
DISPLAY INVISIBLE (-6425 4225);
FORCEPROP 1 LAST PATH I1971
J 0
(-6400 4450);
DISPLAY 0.978723 (-6400 4450);
PAINT WHITE (-6400 4450);
DISPLAY INVISIBLE (-6400 4450);
FORCEPROP 2 LAST BOM_COST MEM
J 2
(-6325 4450);
DISPLAY 0.744681 (-6325 4450);
PAINT WHITE (-6325 4450);
DISPLAY INVISIBLE (-6325 4450);
FORCEPROP 2 LAST CDS_LIB pure_quanta
J 0
(-6350 4300);
DISPLAY INVISIBLE (-6350 4300);
FORCEADD Q_RES..1
(-6350 4100);
FORCEPROP 1 LAST LOCATION R1280
J 0
(-6225 4100);
DISPLAY 0.489362 (-6225 4100);
PAINT SKYBLUE (-6225 4100);
FORCEPROP 0 LAST $SEC 1
J 0
(-6225 4150);
DISPLAY 0.680851 (-6225 4150);
PAINT MONO (-6225 4150);
DISPLAY INVISIBLE (-6225 4150);
FORCEPROP 0 LAST CDS_SEC 1
J 0
(-6225 4150);
DISPLAY 0.680851 (-6225 4150);
DISPLAY INVISIBLE (-6225 4150);
FORCEPROP 1 LASTPIN (-6450 4100) $PN 1
J 0
(-6438 4112);
DISPLAY 0.489362 (-6438 4112);
PAINT MONO (-6438 4112);
FORCEPROP 1 LASTPIN (-6250 4100) $PN 2
J 0
(-6288 4112);
DISPLAY 0.489362 (-6288 4112);
PAINT MONO (-6288 4112);
FORCEPROP 1 LAST VALUE 33
J 2
(-6475 4100);
DISPLAY 0.489362 (-6475 4100);
PAINT SKYBLUE (-6475 4100);
FORCEPROP 2 LAST ROOM RST_CPU0_PLD_TO_DIMM
J 2
(-6325 4200);
DISPLAY 0.744681 (-6325 4200);
PAINT RED (-6325 4200);
DISPLAY INVISIBLE (-6325 4200);
FORCEPROP 1 LAST PACK_TYPE 0402LF
J 2
(-6175 4025);
DISPLAY 0.489362 (-6175 4025);
PAINT SKYBLUE (-6175 4025);
DISPLAY INVISIBLE (-6175 4025);
FORCEPROP 1 LAST PART_NUMBER CS03302JB29
J 2
(-6250 4150);
DISPLAY 0.489362 (-6250 4150);
PAINT SKYBLUE (-6250 4150);
DISPLAY INVISIBLE (-6250 4150);
FORCEPROP 1 LAST TOLERANCE 5%
J 0
(-6475 4075);
DISPLAY 0.489362 (-6475 4075);
PAINT SKYBLUE (-6475 4075);
DISPLAY INVISIBLE (-6475 4075);
FORCEPROP 1 LAST MATERIAL CHIP
J 2
(-6175 4075);
DISPLAY 0.489362 (-6175 4075);
PAINT SKYBLUE (-6175 4075);
DISPLAY INVISIBLE (-6175 4075);
FORCEPROP 1 LAST WATTAGE 1/16W
J 2
(-6425 4025);
DISPLAY 0.489362 (-6425 4025);
PAINT SKYBLUE (-6425 4025);
DISPLAY INVISIBLE (-6425 4025);
FORCEPROP 1 LAST PATH I1972
J 0
(-6400 4250);
DISPLAY 0.978723 (-6400 4250);
PAINT WHITE (-6400 4250);
DISPLAY INVISIBLE (-6400 4250);
FORCEPROP 2 LAST BOM_COST MEM
J 2
(-6325 4250);
DISPLAY 0.744681 (-6325 4250);
PAINT WHITE (-6325 4250);
DISPLAY INVISIBLE (-6325 4250);
FORCEPROP 2 LAST CDS_LIB pure_quanta
J 0
(-6350 4100);
DISPLAY INVISIBLE (-6350 4100);
FORCEADD Q_RES..1
(-6350 4150);
FORCEPROP 1 LAST LOCATION R1281
J 0
(-6225 4150);
DISPLAY 0.489362 (-6225 4150);
PAINT SKYBLUE (-6225 4150);
FORCEPROP 0 LAST $SEC 1
J 0
(-6225 4200);
DISPLAY 0.680851 (-6225 4200);
PAINT MONO (-6225 4200);
DISPLAY INVISIBLE (-6225 4200);
FORCEPROP 0 LAST CDS_SEC 1
J 0
(-6225 4200);
DISPLAY 0.680851 (-6225 4200);
DISPLAY INVISIBLE (-6225 4200);
FORCEPROP 1 LASTPIN (-6450 4150) $PN 1
J 0
(-6438 4162);
DISPLAY 0.489362 (-6438 4162);
PAINT MONO (-6438 4162);
FORCEPROP 1 LASTPIN (-6250 4150) $PN 2
J 0
(-6288 4162);
DISPLAY 0.489362 (-6288 4162);
PAINT MONO (-6288 4162);
FORCEPROP 1 LAST VALUE 33
J 2
(-6475 4150);
DISPLAY 0.489362 (-6475 4150);
PAINT SKYBLUE (-6475 4150);
FORCEPROP 2 LAST ROOM RST_CPU0_PLD_TO_DIMM
J 2
(-6325 4250);
DISPLAY 0.744681 (-6325 4250);
PAINT RED (-6325 4250);
DISPLAY INVISIBLE (-6325 4250);
FORCEPROP 1 LAST PACK_TYPE 0402LF
J 2
(-6175 4075);
DISPLAY 0.489362 (-6175 4075);
PAINT SKYBLUE (-6175 4075);
DISPLAY INVISIBLE (-6175 4075);
FORCEPROP 1 LAST PART_NUMBER CS03302JB29
J 2
(-6250 4200);
DISPLAY 0.489362 (-6250 4200);
PAINT SKYBLUE (-6250 4200);
DISPLAY INVISIBLE (-6250 4200);
FORCEPROP 1 LAST TOLERANCE 5%
J 0
(-6475 4125);
DISPLAY 0.489362 (-6475 4125);
PAINT SKYBLUE (-6475 4125);
DISPLAY INVISIBLE (-6475 4125);
FORCEPROP 1 LAST MATERIAL CHIP
J 2
(-6175 4125);
DISPLAY 0.489362 (-6175 4125);
PAINT SKYBLUE (-6175 4125);
DISPLAY INVISIBLE (-6175 4125);
FORCEPROP 1 LAST WATTAGE 1/16W
J 2
(-6425 4075);
DISPLAY 0.489362 (-6425 4075);
PAINT SKYBLUE (-6425 4075);
DISPLAY INVISIBLE (-6425 4075);
FORCEPROP 1 LAST PATH I1973
J 0
(-6400 4300);
DISPLAY 0.978723 (-6400 4300);
PAINT WHITE (-6400 4300);
DISPLAY INVISIBLE (-6400 4300);
FORCEPROP 2 LAST BOM_COST MEM
J 2
(-6325 4300);
DISPLAY 0.744681 (-6325 4300);
PAINT WHITE (-6325 4300);
DISPLAY INVISIBLE (-6325 4300);
FORCEPROP 2 LAST CDS_LIB pure_quanta
J 0
(-6350 4150);
DISPLAY INVISIBLE (-6350 4150);
FORCEADD Q_RES..1
(-6350 3950);
FORCEPROP 1 LAST LOCATION R194
J 0
(-6225 3950);
DISPLAY 0.489362 (-6225 3950);
PAINT SKYBLUE (-6225 3950);
FORCEPROP 0 LAST $SEC 1
J 2
(-6225 4000);
DISPLAY 0.680851 (-6225 4000);
PAINT MONO (-6225 4000);
DISPLAY INVISIBLE (-6225 4000);
FORCEPROP 0 LAST CDS_SEC 1
J 2
(-6225 4000);
DISPLAY 1.021277 (-6225 4000);
DISPLAY INVISIBLE (-6225 4000);
FORCEPROP 1 LASTPIN (-6450 3950) $PN 1
J 0
(-6438 3962);
DISPLAY 0.489362 (-6438 3962);
PAINT MONO (-6438 3962);
FORCEPROP 1 LASTPIN (-6250 3950) $PN 2
J 0
(-6288 3962);
DISPLAY 0.489362 (-6288 3962);
PAINT MONO (-6288 3962);
FORCEPROP 1 LAST VALUE 0
J 2
(-6475 3950);
DISPLAY 0.489362 (-6475 3950);
PAINT SKYBLUE (-6475 3950);
FORCEPROP 2 LAST ROOM RST_CPU0_PLD_TO_DIMM
J 2
(-6325 4050);
DISPLAY 0.744681 (-6325 4050);
PAINT RED (-6325 4050);
DISPLAY INVISIBLE (-6325 4050);
FORCEPROP 1 LAST PACK_TYPE 0402LF
J 2
(-6175 3875);
DISPLAY 0.489362 (-6175 3875);
PAINT SKYBLUE (-6175 3875);
DISPLAY INVISIBLE (-6175 3875);
FORCEPROP 1 LAST PART_NUMBER CS00002JB38
J 2
(-6250 4000);
DISPLAY 0.489362 (-6250 4000);
PAINT SKYBLUE (-6250 4000);
DISPLAY INVISIBLE (-6250 4000);
FORCEPROP 1 LAST TOLERANCE 5%
J 0
(-6475 3925);
DISPLAY 0.489362 (-6475 3925);
PAINT SKYBLUE (-6475 3925);
DISPLAY INVISIBLE (-6475 3925);
FORCEPROP 1 LAST MATERIAL CHIP
J 2
(-6175 3925);
DISPLAY 0.489362 (-6175 3925);
PAINT SKYBLUE (-6175 3925);
DISPLAY INVISIBLE (-6175 3925);
FORCEPROP 1 LAST WATTAGE 1/16W
J 2
(-6425 3875);
DISPLAY 0.489362 (-6425 3875);
PAINT SKYBLUE (-6425 3875);
DISPLAY INVISIBLE (-6425 3875);
FORCEPROP 1 LAST PATH I1974
J 0
(-6400 4100);
DISPLAY 0.978723 (-6400 4100);
PAINT WHITE (-6400 4100);
DISPLAY INVISIBLE (-6400 4100);
FORCEPROP 2 LAST BOM_COST MEM
J 2
(-6325 4100);
DISPLAY 0.744681 (-6325 4100);
PAINT WHITE (-6325 4100);
DISPLAY INVISIBLE (-6325 4100);
FORCEPROP 2 LAST CDS_LIB pure_quanta
J 2
(-6350 3950);
DISPLAY INVISIBLE (-6350 3950);
FORCEADD OFFPAGE..4
R 2
(-7275 6000);
FORCEPROP 2 LAST $XR0 28 
J 0
(-7496 6000);
DISPLAY 0.638298 (-7496 6000);
PAINT MONO (-7496 6000);
FORCEPROP 2 LAST CDS_LIB standard
J 0
(-7275 6000);
DISPLAY INVISIBLE (-7275 6000);
FORCEPROP 1 LAST OFFPAGE TRUE
J 2
(-7600 5875);
DISPLAY 0.872340 (-7600 5875);
PAINT GREEN (-7600 5875);
DISPLAY INVISIBLE (-7600 5875);
FORCEPROP 1 LAST COMMENT_BODY TRUE
J 2
(-7250 5900);
DISPLAY 0.872340 (-7250 5900);
PAINT GREEN (-7250 5900);
DISPLAY INVISIBLE (-7250 5900);
FORCEPROP 2 LAST PATH I1975
J 0
(-7225 6075);
DISPLAY 0.680851 (-7225 6075);
DISPLAY INVISIBLE (-7225 6075);
FORCEADD OFFPAGE..4
R 2
(-7275 5800);
FORCEPROP 2 LAST $XR0 55 
J 0
(-7496 5800);
DISPLAY 0.638298 (-7496 5800);
PAINT MONO (-7496 5800);
FORCEPROP 1 LAST COMMENT_BODY TRUE
J 2
(-7250 5700);
DISPLAY 0.872340 (-7250 5700);
PAINT GREEN (-7250 5700);
DISPLAY INVISIBLE (-7250 5700);
FORCEPROP 1 LAST OFFPAGE TRUE
J 2
(-7600 5675);
DISPLAY 0.872340 (-7600 5675);
PAINT GREEN (-7600 5675);
DISPLAY INVISIBLE (-7600 5675);
FORCEPROP 2 LAST CDS_LIB standard
J 0
(-7275 5800);
DISPLAY INVISIBLE (-7275 5800);
FORCEPROP 2 LAST PATH I1976
J 0
(-7225 5875);
DISPLAY 0.680851 (-7225 5875);
DISPLAY INVISIBLE (-7225 5875);
FORCEADD OFFPAGE..4
R 2
(-7275 5950);
FORCEPROP 2 LAST $XR0 28 
J 0
(-7496 5950);
DISPLAY 0.638298 (-7496 5950);
PAINT MONO (-7496 5950);
FORCEPROP 2 LAST CDS_LIB standard
J 0
(-7275 5950);
DISPLAY INVISIBLE (-7275 5950);
FORCEPROP 1 LAST COMMENT_BODY TRUE
J 2
(-7250 5850);
DISPLAY 0.872340 (-7250 5850);
PAINT GREEN (-7250 5850);
DISPLAY INVISIBLE (-7250 5850);
FORCEPROP 1 LAST OFFPAGE TRUE
J 2
(-7600 5825);
DISPLAY 0.872340 (-7600 5825);
PAINT GREEN (-7600 5825);
DISPLAY INVISIBLE (-7600 5825);
FORCEPROP 2 LAST PATH I1977
J 0
(-7225 6025);
DISPLAY 0.680851 (-7225 6025);
DISPLAY INVISIBLE (-7225 6025);
FORCEADD OFFPAGE..4
R 2
(-7275 5850);
FORCEPROP 2 LAST $XR1 82 
J 0
(-7586 5850);
DISPLAY 0.638298 (-7586 5850);
PAINT MONO (-7586 5850);
FORCEPROP 2 LAST $XR0 55 
J 0
(-7496 5850);
DISPLAY 0.638298 (-7496 5850);
PAINT MONO (-7496 5850);
FORCEPROP 2 LAST CDS_LIB standard
J 0
(-7275 5850);
DISPLAY INVISIBLE (-7275 5850);
FORCEPROP 1 LAST COMMENT_BODY TRUE
J 2
(-7250 5750);
DISPLAY 0.872340 (-7250 5750);
PAINT GREEN (-7250 5750);
DISPLAY INVISIBLE (-7250 5750);
FORCEPROP 1 LAST OFFPAGE TRUE
J 2
(-7600 5725);
DISPLAY 0.872340 (-7600 5725);
PAINT GREEN (-7600 5725);
DISPLAY INVISIBLE (-7600 5725);
FORCEPROP 2 LAST PATH I1978
J 0
(-7225 5925);
DISPLAY 0.680851 (-7225 5925);
DISPLAY INVISIBLE (-7225 5925);
FORCEADD OFFPAGE..4
R 2
(-7275 5900);
FORCEPROP 2 LAST $XR1 82 
J 0
(-7586 5900);
DISPLAY 0.638298 (-7586 5900);
PAINT MONO (-7586 5900);
FORCEPROP 2 LAST $XR0 28 
J 0
(-7496 5900);
DISPLAY 0.638298 (-7496 5900);
PAINT MONO (-7496 5900);
FORCEPROP 2 LAST CDS_LIB standard
J 0
(-7275 5900);
DISPLAY INVISIBLE (-7275 5900);
FORCEPROP 1 LAST OFFPAGE TRUE
J 2
(-7600 5775);
DISPLAY 0.872340 (-7600 5775);
PAINT GREEN (-7600 5775);
DISPLAY INVISIBLE (-7600 5775);
FORCEPROP 1 LAST COMMENT_BODY TRUE
J 2
(-7250 5800);
DISPLAY 0.872340 (-7250 5800);
PAINT GREEN (-7250 5800);
DISPLAY INVISIBLE (-7250 5800);
FORCEPROP 2 LAST PATH I1979
J 0
(-7225 5975);
DISPLAY 0.680851 (-7225 5975);
DISPLAY INVISIBLE (-7225 5975);
FORCEADD OFFPAGE..4
R 2
(-7275 5750);
FORCEPROP 2 LAST $XR0 55 
J 0
(-7496 5750);
DISPLAY 0.638298 (-7496 5750);
PAINT MONO (-7496 5750);
FORCEPROP 1 LAST OFFPAGE TRUE
J 2
(-7600 5625);
DISPLAY 0.872340 (-7600 5625);
PAINT GREEN (-7600 5625);
DISPLAY INVISIBLE (-7600 5625);
FORCEPROP 1 LAST COMMENT_BODY TRUE
J 2
(-7250 5650);
DISPLAY 0.872340 (-7250 5650);
PAINT GREEN (-7250 5650);
DISPLAY INVISIBLE (-7250 5650);
FORCEPROP 2 LAST CDS_LIB standard
J 0
(-7275 5750);
DISPLAY INVISIBLE (-7275 5750);
FORCEPROP 2 LAST PATH I1980
J 0
(-7225 5825);
DISPLAY 0.680851 (-7225 5825);
DISPLAY INVISIBLE (-7225 5825);
FORCEADD OFFPAGE..4
R 2
(-7275 5600);
FORCEPROP 2 LAST $XR0 140 
J 0
(-7527 5600);
DISPLAY 0.638298 (-7527 5600);
PAINT MONO (-7527 5600);
FORCEPROP 1 LAST COMMENT_BODY TRUE
J 2
(-7250 5500);
DISPLAY 0.872340 (-7250 5500);
PAINT GREEN (-7250 5500);
DISPLAY INVISIBLE (-7250 5500);
FORCEPROP 1 LAST OFFPAGE TRUE
J 2
(-7600 5475);
DISPLAY 0.872340 (-7600 5475);
PAINT GREEN (-7600 5475);
DISPLAY INVISIBLE (-7600 5475);
FORCEPROP 2 LAST CDS_LIB standard
J 0
(-7275 5600);
DISPLAY INVISIBLE (-7275 5600);
FORCEPROP 2 LAST PATH I1981
J 0
(-7225 5675);
DISPLAY 0.680851 (-7225 5675);
DISPLAY INVISIBLE (-7225 5675);
FORCEADD OFFPAGE..4
R 2
(-7275 5550);
FORCEPROP 2 LAST $XR0 140 
J 0
(-7527 5550);
DISPLAY 0.638298 (-7527 5550);
PAINT MONO (-7527 5550);
FORCEPROP 1 LAST COMMENT_BODY TRUE
J 2
(-7250 5450);
DISPLAY 0.872340 (-7250 5450);
PAINT GREEN (-7250 5450);
DISPLAY INVISIBLE (-7250 5450);
FORCEPROP 1 LAST OFFPAGE TRUE
J 2
(-7600 5425);
DISPLAY 0.872340 (-7600 5425);
PAINT GREEN (-7600 5425);
DISPLAY INVISIBLE (-7600 5425);
FORCEPROP 2 LAST CDS_LIB standard
J 0
(-7275 5550);
DISPLAY INVISIBLE (-7275 5550);
FORCEPROP 2 LAST PATH I1982
J 0
(-7225 5625);
DISPLAY 0.680851 (-7225 5625);
DISPLAY INVISIBLE (-7225 5625);
FORCEADD OFFPAGE..4
R 2
(-7275 5700);
FORCEPROP 2 LAST $XR1 115 
J 0
(-7616 5700);
DISPLAY 0.638298 (-7616 5700);
PAINT MONO (-7616 5700);
FORCEPROP 2 LAST $XR0 82 
J 0
(-7496 5700);
DISPLAY 0.638298 (-7496 5700);
PAINT MONO (-7496 5700);
FORCEPROP 2 LAST CDS_LIB standard
J 0
(-7275 5700);
DISPLAY INVISIBLE (-7275 5700);
FORCEPROP 1 LAST OFFPAGE TRUE
J 2
(-7600 5575);
DISPLAY 0.872340 (-7600 5575);
PAINT GREEN (-7600 5575);
DISPLAY INVISIBLE (-7600 5575);
FORCEPROP 1 LAST COMMENT_BODY TRUE
J 2
(-7250 5600);
DISPLAY 0.872340 (-7250 5600);
PAINT GREEN (-7250 5600);
DISPLAY INVISIBLE (-7250 5600);
FORCEPROP 2 LAST PATH I1983
J 0
(-7225 5775);
DISPLAY 0.680851 (-7225 5775);
DISPLAY INVISIBLE (-7225 5775);
FORCEADD OFFPAGE..4
R 2
(-7275 5650);
FORCEPROP 2 LAST $XR1 82 
J 0
(-7586 5650);
DISPLAY 0.638298 (-7586 5650);
PAINT MONO (-7586 5650);
FORCEPROP 2 LAST $XR0 28 
J 0
(-7496 5650);
DISPLAY 0.638298 (-7496 5650);
PAINT MONO (-7496 5650);
FORCEPROP 2 LAST CDS_LIB standard
J 0
(-7275 5650);
DISPLAY INVISIBLE (-7275 5650);
FORCEPROP 1 LAST OFFPAGE TRUE
J 2
(-7600 5525);
DISPLAY 0.872340 (-7600 5525);
PAINT GREEN (-7600 5525);
DISPLAY INVISIBLE (-7600 5525);
FORCEPROP 1 LAST COMMENT_BODY TRUE
J 2
(-7250 5550);
DISPLAY 0.872340 (-7250 5550);
PAINT GREEN (-7250 5550);
DISPLAY INVISIBLE (-7250 5550);
FORCEPROP 2 LAST PATH I1984
J 0
(-7225 5725);
DISPLAY 0.680851 (-7225 5725);
DISPLAY INVISIBLE (-7225 5725);
FORCEADD OFFPAGE..4
R 2
(-7275 5500);
FORCEPROP 2 LAST $XR1 82 
J 0
(-7586 5500);
DISPLAY 0.638298 (-7586 5500);
PAINT MONO (-7586 5500);
FORCEPROP 2 LAST $XR0 55 
J 0
(-7496 5500);
DISPLAY 0.638298 (-7496 5500);
PAINT MONO (-7496 5500);
FORCEPROP 2 LAST CDS_LIB standard
J 0
(-7275 5500);
DISPLAY INVISIBLE (-7275 5500);
FORCEPROP 1 LAST OFFPAGE TRUE
J 2
(-7600 5375);
DISPLAY 0.872340 (-7600 5375);
PAINT GREEN (-7600 5375);
DISPLAY INVISIBLE (-7600 5375);
FORCEPROP 1 LAST COMMENT_BODY TRUE
J 2
(-7250 5400);
DISPLAY 0.872340 (-7250 5400);
PAINT GREEN (-7250 5400);
DISPLAY INVISIBLE (-7250 5400);
FORCEPROP 2 LAST PATH I1985
J 0
(-7225 5575);
DISPLAY 0.680851 (-7225 5575);
DISPLAY INVISIBLE (-7225 5575);
FORCEADD OFFPAGE..4
R 2
(-7275 5400);
FORCEPROP 2 LAST $XR0 55 
J 0
(-7496 5400);
DISPLAY 0.638298 (-7496 5400);
PAINT MONO (-7496 5400);
FORCEPROP 2 LAST CDS_LIB standard
J 0
(-7275 5400);
DISPLAY INVISIBLE (-7275 5400);
FORCEPROP 1 LAST OFFPAGE TRUE
J 2
(-7600 5275);
DISPLAY 0.872340 (-7600 5275);
PAINT GREEN (-7600 5275);
DISPLAY INVISIBLE (-7600 5275);
FORCEPROP 1 LAST COMMENT_BODY TRUE
J 2
(-7250 5300);
DISPLAY 0.872340 (-7250 5300);
PAINT GREEN (-7250 5300);
DISPLAY INVISIBLE (-7250 5300);
FORCEPROP 2 LAST PATH I1986
J 0
(-7225 5475);
DISPLAY 0.680851 (-7225 5475);
DISPLAY INVISIBLE (-7225 5475);
FORCEADD OFFPAGE..4
R 2
(-7275 5450);
FORCEPROP 2 LAST $XR1 114 
J 0
(-7616 5450);
DISPLAY 0.638298 (-7616 5450);
PAINT MONO (-7616 5450);
FORCEPROP 2 LAST $XR0 82 
J 0
(-7496 5450);
DISPLAY 0.638298 (-7496 5450);
PAINT MONO (-7496 5450);
FORCEPROP 2 LAST CDS_LIB standard
J 0
(-7275 5450);
DISPLAY INVISIBLE (-7275 5450);
FORCEPROP 1 LAST OFFPAGE TRUE
J 2
(-7600 5325);
DISPLAY 0.872340 (-7600 5325);
PAINT GREEN (-7600 5325);
DISPLAY INVISIBLE (-7600 5325);
FORCEPROP 1 LAST COMMENT_BODY TRUE
J 2
(-7250 5350);
DISPLAY 0.872340 (-7250 5350);
PAINT GREEN (-7250 5350);
DISPLAY INVISIBLE (-7250 5350);
FORCEPROP 2 LAST PATH I1987
J 0
(-7225 5525);
DISPLAY 0.680851 (-7225 5525);
DISPLAY INVISIBLE (-7225 5525);
FORCEADD OFFPAGE..4
R 2
(-7275 5350);
FORCEPROP 2 LAST $XR0 28 
J 0
(-7496 5350);
DISPLAY 0.638298 (-7496 5350);
PAINT MONO (-7496 5350);
FORCEPROP 2 LAST CDS_LIB standard
J 0
(-7275 5350);
DISPLAY INVISIBLE (-7275 5350);
FORCEPROP 1 LAST OFFPAGE TRUE
J 2
(-7600 5225);
DISPLAY 0.872340 (-7600 5225);
PAINT GREEN (-7600 5225);
DISPLAY INVISIBLE (-7600 5225);
FORCEPROP 1 LAST COMMENT_BODY TRUE
J 2
(-7250 5250);
DISPLAY 0.872340 (-7250 5250);
PAINT GREEN (-7250 5250);
DISPLAY INVISIBLE (-7250 5250);
FORCEPROP 2 LAST PATH I1988
J 0
(-7225 5425);
DISPLAY 0.680851 (-7225 5425);
DISPLAY INVISIBLE (-7225 5425);
FORCEADD OFFPAGE..4
R 2
(-7275 5300);
FORCEPROP 2 LAST $XR1 114 
J 0
(-7616 5300);
DISPLAY 0.638298 (-7616 5300);
PAINT MONO (-7616 5300);
FORCEPROP 2 LAST $XR0 82 
J 0
(-7496 5300);
DISPLAY 0.638298 (-7496 5300);
PAINT MONO (-7496 5300);
FORCEPROP 2 LAST CDS_LIB standard
J 0
(-7275 5300);
DISPLAY INVISIBLE (-7275 5300);
FORCEPROP 1 LAST OFFPAGE TRUE
J 2
(-7600 5175);
DISPLAY 0.872340 (-7600 5175);
PAINT GREEN (-7600 5175);
DISPLAY INVISIBLE (-7600 5175);
FORCEPROP 1 LAST COMMENT_BODY TRUE
J 2
(-7250 5200);
DISPLAY 0.872340 (-7250 5200);
PAINT GREEN (-7250 5200);
DISPLAY INVISIBLE (-7250 5200);
FORCEPROP 2 LAST PATH I1989
J 0
(-7225 5375);
DISPLAY 0.680851 (-7225 5375);
DISPLAY INVISIBLE (-7225 5375);
FORCEADD OFFPAGE..2
R 2
(-7275 5250);
FORCEPROP 2 LAST $XR0 28 
J 0
(-7529 5250);
DISPLAY 0.638298 (-7529 5250);
PAINT MONO (-7529 5250);
FORCEPROP 2 LAST CDS_LIB standard
J 0
(-7275 5250);
DISPLAY INVISIBLE (-7275 5250);
FORCEPROP 1 LAST OFFPAGE TRUE
J 2
(-7600 5125);
DISPLAY 0.872340 (-7600 5125);
PAINT GREEN (-7600 5125);
DISPLAY INVISIBLE (-7600 5125);
FORCEPROP 1 LAST COMMENT_BODY TRUE
J 2
(-7230 5155);
DISPLAY 0.872340 (-7230 5155);
PAINT GREEN (-7230 5155);
DISPLAY INVISIBLE (-7230 5155);
FORCEPROP 2 LAST PATH I1990
J 0
(-7225 5325);
DISPLAY 0.680851 (-7225 5325);
DISPLAY INVISIBLE (-7225 5325);
FORCEADD OFFPAGE..2
R 2
(-7275 5200);
FORCEPROP 2 LAST $XR0 55 
J 0
(-7529 5200);
DISPLAY 0.638298 (-7529 5200);
PAINT MONO (-7529 5200);
FORCEPROP 2 LAST CDS_LIB standard
J 0
(-7275 5200);
DISPLAY INVISIBLE (-7275 5200);
FORCEPROP 1 LAST OFFPAGE TRUE
J 2
(-7600 5075);
DISPLAY 0.872340 (-7600 5075);
PAINT GREEN (-7600 5075);
DISPLAY INVISIBLE (-7600 5075);
FORCEPROP 1 LAST COMMENT_BODY TRUE
J 2
(-7230 5105);
DISPLAY 0.872340 (-7230 5105);
PAINT GREEN (-7230 5105);
DISPLAY INVISIBLE (-7230 5105);
FORCEPROP 2 LAST PATH I1991
J 0
(-7225 5275);
DISPLAY 0.680851 (-7225 5275);
DISPLAY INVISIBLE (-7225 5275);
FORCEADD OFFPAGE..4
R 2
(-7275 5150);
FORCEPROP 2 LAST $XR0 28 
J 0
(-7526 5150);
DISPLAY 0.638298 (-7526 5150);
PAINT MONO (-7526 5150);
FORCEPROP 2 LAST CDS_LIB standard
J 0
(-7275 5150);
DISPLAY INVISIBLE (-7275 5150);
FORCEPROP 1 LAST COMMENT_BODY TRUE
J 2
(-7250 5050);
DISPLAY 0.872340 (-7250 5050);
PAINT GREEN (-7250 5050);
DISPLAY INVISIBLE (-7250 5050);
FORCEPROP 1 LAST OFFPAGE TRUE
J 2
(-7600 5025);
DISPLAY 0.872340 (-7600 5025);
PAINT GREEN (-7600 5025);
DISPLAY INVISIBLE (-7600 5025);
FORCEPROP 2 LAST PATH I1992
J 0
(-7225 5225);
DISPLAY 0.680851 (-7225 5225);
DISPLAY INVISIBLE (-7225 5225);
FORCEADD OFFPAGE..4
R 2
(-7275 5100);
FORCEPROP 2 LAST $XR1 115 
J 0
(-7616 5100);
DISPLAY 0.638298 (-7616 5100);
PAINT MONO (-7616 5100);
FORCEPROP 2 LAST $XR0 82 
J 0
(-7496 5100);
DISPLAY 0.638298 (-7496 5100);
PAINT MONO (-7496 5100);
FORCEPROP 1 LAST COMMENT_BODY TRUE
J 2
(-7250 5000);
DISPLAY 0.872340 (-7250 5000);
PAINT GREEN (-7250 5000);
DISPLAY INVISIBLE (-7250 5000);
FORCEPROP 1 LAST OFFPAGE TRUE
J 2
(-7600 4975);
DISPLAY 0.872340 (-7600 4975);
PAINT GREEN (-7600 4975);
DISPLAY INVISIBLE (-7600 4975);
FORCEPROP 2 LAST CDS_LIB standard
J 0
(-7275 5100);
DISPLAY INVISIBLE (-7275 5100);
FORCEPROP 2 LAST PATH I1993
J 0
(-7225 5175);
DISPLAY 0.680851 (-7225 5175);
DISPLAY INVISIBLE (-7225 5175);
FORCEADD OFFPAGE..4
R 2
(-7275 5050);
FORCEPROP 2 LAST $XR1 114 
J 0
(-7616 5050);
DISPLAY 0.638298 (-7616 5050);
PAINT MONO (-7616 5050);
FORCEPROP 2 LAST $XR0 82 
J 0
(-7496 5050);
DISPLAY 0.638298 (-7496 5050);
PAINT MONO (-7496 5050);
FORCEPROP 2 LAST CDS_LIB standard
J 0
(-7275 5050);
DISPLAY INVISIBLE (-7275 5050);
FORCEPROP 1 LAST COMMENT_BODY TRUE
J 2
(-7250 4950);
DISPLAY 0.872340 (-7250 4950);
PAINT GREEN (-7250 4950);
DISPLAY INVISIBLE (-7250 4950);
FORCEPROP 1 LAST OFFPAGE TRUE
J 2
(-7600 4925);
DISPLAY 0.872340 (-7600 4925);
PAINT GREEN (-7600 4925);
DISPLAY INVISIBLE (-7600 4925);
FORCEPROP 2 LAST PATH I1994
J 0
(-7225 5125);
DISPLAY 0.680851 (-7225 5125);
DISPLAY INVISIBLE (-7225 5125);
FORCEADD OFFPAGE..3
R 2
(-7275 5000);
FORCEPROP 2 LAST $XR1 84 
J 0
(-7644 5000);
DISPLAY 0.638298 (-7644 5000);
PAINT MONO (-7644 5000);
FORCEPROP 2 LAST $XR0 28 
J 0
(-7554 5000);
DISPLAY 0.638298 (-7554 5000);
PAINT MONO (-7554 5000);
FORCEPROP 2 LAST CDS_LIB standard
J 0
(-7275 5000);
DISPLAY INVISIBLE (-7275 5000);
FORCEPROP 1 LAST OFFPAGE TRUE
J 2
(-7600 4875);
DISPLAY 0.872340 (-7600 4875);
PAINT GREEN (-7600 4875);
DISPLAY INVISIBLE (-7600 4875);
FORCEPROP 1 LAST COMMENT_BODY TRUE
J 2
(-7225 4900);
DISPLAY 0.872340 (-7225 4900);
PAINT GREEN (-7225 4900);
DISPLAY INVISIBLE (-7225 4900);
FORCEPROP 2 LAST PATH I1995
J 0
(-7225 5075);
DISPLAY 0.680851 (-7225 5075);
DISPLAY INVISIBLE (-7225 5075);
FORCEADD OFFPAGE..2
R 2
(-7275 4900);
FORCEPROP 2 LAST $XR1 29 
J 0
(-7619 4900);
DISPLAY 0.638298 (-7619 4900);
PAINT MONO (-7619 4900);
FORCEPROP 2 LAST $XR0 82 
J 0
(-7529 4900);
DISPLAY 0.638298 (-7529 4900);
PAINT MONO (-7529 4900);
FORCEPROP 1 LAST COMMENT_BODY TRUE
J 2
(-7230 4805);
DISPLAY 0.872340 (-7230 4805);
PAINT GREEN (-7230 4805);
DISPLAY INVISIBLE (-7230 4805);
FORCEPROP 1 LAST OFFPAGE TRUE
J 2
(-7600 4775);
DISPLAY 0.872340 (-7600 4775);
PAINT GREEN (-7600 4775);
DISPLAY INVISIBLE (-7600 4775);
FORCEPROP 2 LAST PATH I1996
J 0
(-7225 4975);
DISPLAY 0.680851 (-7225 4975);
DISPLAY INVISIBLE (-7225 4975);
FORCEPROP 2 LAST CDS_LIB standard
J 0
(-7275 4900);
DISPLAY INVISIBLE (-7275 4900);
FORCEADD OFFPAGE..3
R 2
(-7275 4950);
FORCEPROP 2 LAST $XR1 84 
J 0
(-7644 4950);
DISPLAY 0.638298 (-7644 4950);
PAINT MONO (-7644 4950);
FORCEPROP 2 LAST $XR0 55 
J 0
(-7554 4950);
DISPLAY 0.638298 (-7554 4950);
PAINT MONO (-7554 4950);
FORCEPROP 2 LAST CDS_LIB standard
J 0
(-7275 4950);
DISPLAY INVISIBLE (-7275 4950);
FORCEPROP 1 LAST OFFPAGE TRUE
J 2
(-7600 4825);
DISPLAY 0.872340 (-7600 4825);
PAINT GREEN (-7600 4825);
DISPLAY INVISIBLE (-7600 4825);
FORCEPROP 1 LAST COMMENT_BODY TRUE
J 2
(-7225 4850);
DISPLAY 0.872340 (-7225 4850);
PAINT GREEN (-7225 4850);
DISPLAY INVISIBLE (-7225 4850);
FORCEPROP 2 LAST PATH I1997
J 0
(-7225 5025);
DISPLAY 0.680851 (-7225 5025);
DISPLAY INVISIBLE (-7225 5025);
FORCEADD OFFPAGE..4
R 2
(-7275 4750);
FORCEPROP 2 LAST $XR0 55 
J 0
(-7556 4750);
DISPLAY 0.638298 (-7556 4750);
PAINT MONO (-7556 4750);
FORCEPROP 2 LAST CDS_LIB standard
J 0
(-7275 4750);
DISPLAY INVISIBLE (-7275 4750);
FORCEPROP 2 LAST PATH I1999
J 0
(-7225 4825);
DISPLAY 0.680851 (-7225 4825);
DISPLAY INVISIBLE (-7225 4825);
FORCEPROP 1 LAST OFFPAGE TRUE
J 2
(-7600 4625);
DISPLAY 0.872340 (-7600 4625);
PAINT GREEN (-7600 4625);
DISPLAY INVISIBLE (-7600 4625);
FORCEPROP 1 LAST COMMENT_BODY TRUE
J 2
(-7250 4650);
DISPLAY 0.872340 (-7250 4650);
PAINT GREEN (-7250 4650);
DISPLAY INVISIBLE (-7250 4650);
FORCEADD OFFPAGE..3
R 2
(-7275 4800);
FORCEPROP 2 LAST $XR2 84 
J 0
(-7734 4800);
DISPLAY 0.638298 (-7734 4800);
PAINT MONO (-7734 4800);
FORCEPROP 2 LAST $XR1 77 
J 0
(-7644 4800);
DISPLAY 0.638298 (-7644 4800);
PAINT MONO (-7644 4800);
FORCEPROP 2 LAST $XR0 28 
J 0
(-7554 4800);
DISPLAY 0.638298 (-7554 4800);
PAINT MONO (-7554 4800);
FORCEPROP 2 LAST CDS_LIB standard
J 0
(-7275 4800);
DISPLAY INVISIBLE (-7275 4800);
FORCEPROP 1 LAST OFFPAGE TRUE
J 2
(-7600 4675);
DISPLAY 0.872340 (-7600 4675);
PAINT GREEN (-7600 4675);
DISPLAY INVISIBLE (-7600 4675);
FORCEPROP 1 LAST COMMENT_BODY TRUE
J 2
(-7225 4700);
DISPLAY 0.872340 (-7225 4700);
PAINT GREEN (-7225 4700);
DISPLAY INVISIBLE (-7225 4700);
FORCEPROP 2 LAST PATH I2000
J 0
(-7225 4875);
DISPLAY 0.680851 (-7225 4875);
DISPLAY INVISIBLE (-7225 4875);
FORCEADD OFFPAGE..2
R 2
(-7275 4650);
FORCEPROP 2 LAST $XR0 200 
J 0
(-7560 4650);
DISPLAY 0.638298 (-7560 4650);
PAINT MONO (-7560 4650);
FORCEPROP 2 LAST CDS_LIB standard
J 0
(-7275 4650);
DISPLAY INVISIBLE (-7275 4650);
FORCEPROP 1 LAST OFFPAGE TRUE
J 2
(-7600 4525);
DISPLAY 0.872340 (-7600 4525);
PAINT GREEN (-7600 4525);
DISPLAY INVISIBLE (-7600 4525);
FORCEPROP 1 LAST COMMENT_BODY TRUE
J 2
(-7230 4555);
DISPLAY 0.872340 (-7230 4555);
PAINT GREEN (-7230 4555);
DISPLAY INVISIBLE (-7230 4555);
FORCEPROP 2 LAST PATH I2001
J 0
(-7225 4725);
DISPLAY 0.680851 (-7225 4725);
DISPLAY INVISIBLE (-7225 4725);
FORCEADD OFFPAGE..2
R 2
(-7275 4700);
FORCEPROP 2 LAST $XR0 183 
J 0
(-7560 4700);
DISPLAY 0.638298 (-7560 4700);
PAINT MONO (-7560 4700);
FORCEPROP 2 LAST CDS_LIB standard
J 0
(-7275 4700);
DISPLAY INVISIBLE (-7275 4700);
FORCEPROP 1 LAST OFFPAGE TRUE
J 2
(-7600 4575);
DISPLAY 0.872340 (-7600 4575);
PAINT GREEN (-7600 4575);
DISPLAY INVISIBLE (-7600 4575);
FORCEPROP 1 LAST COMMENT_BODY TRUE
J 2
(-7230 4605);
DISPLAY 0.872340 (-7230 4605);
PAINT GREEN (-7230 4605);
DISPLAY INVISIBLE (-7230 4605);
FORCEPROP 2 LAST PATH I2002
J 0
(-7225 4775);
DISPLAY 0.680851 (-7225 4775);
DISPLAY INVISIBLE (-7225 4775);
FORCEADD OFFPAGE..2
R 2
(-7275 4600);
FORCEPROP 2 LAST $XR0 28 
J 0
(-7529 4600);
DISPLAY 0.638298 (-7529 4600);
PAINT MONO (-7529 4600);
FORCEPROP 2 LAST CDS_LIB standard
J 0
(-7275 4600);
DISPLAY INVISIBLE (-7275 4600);
FORCEPROP 1 LAST OFFPAGE TRUE
J 2
(-7600 4475);
DISPLAY 0.872340 (-7600 4475);
PAINT GREEN (-7600 4475);
DISPLAY INVISIBLE (-7600 4475);
FORCEPROP 1 LAST COMMENT_BODY TRUE
J 2
(-7230 4505);
DISPLAY 0.872340 (-7230 4505);
PAINT GREEN (-7230 4505);
DISPLAY INVISIBLE (-7230 4505);
FORCEPROP 2 LAST PATH I2003
J 0
(-7225 4675);
DISPLAY 0.680851 (-7225 4675);
DISPLAY INVISIBLE (-7225 4675);
FORCEADD OFFPAGE..3
R 2
(-7275 4500);
FORCEPROP 2 LAST $XR2 77 
J 0
(-7734 4500);
DISPLAY 0.638298 (-7734 4500);
PAINT MONO (-7734 4500);
FORCEPROP 2 LAST $XR1 84 
J 0
(-7644 4500);
DISPLAY 0.638298 (-7644 4500);
PAINT MONO (-7644 4500);
FORCEPROP 2 LAST $XR0 55 
J 0
(-7554 4500);
DISPLAY 0.638298 (-7554 4500);
PAINT MONO (-7554 4500);
FORCEPROP 2 LAST CDS_LIB standard
J 0
(-7275 4500);
DISPLAY INVISIBLE (-7275 4500);
FORCEPROP 1 LAST OFFPAGE TRUE
J 2
(-7600 4375);
DISPLAY 0.872340 (-7600 4375);
PAINT GREEN (-7600 4375);
DISPLAY INVISIBLE (-7600 4375);
FORCEPROP 1 LAST COMMENT_BODY TRUE
J 2
(-7225 4400);
DISPLAY 0.872340 (-7225 4400);
PAINT GREEN (-7225 4400);
DISPLAY INVISIBLE (-7225 4400);
FORCEPROP 2 LAST PATH I2004
J 0
(-7225 4575);
DISPLAY 0.680851 (-7225 4575);
DISPLAY INVISIBLE (-7225 4575);
FORCEADD OFFPAGE..2
R 2
(-7275 4550);
FORCEPROP 2 LAST $XR0 144 
J 0
(-7560 4550);
DISPLAY 0.638298 (-7560 4550);
PAINT MONO (-7560 4550);
FORCEPROP 2 LAST CDS_LIB standard
J 0
(-7275 4550);
DISPLAY INVISIBLE (-7275 4550);
FORCEPROP 1 LAST OFFPAGE TRUE
J 2
(-7600 4425);
DISPLAY 0.872340 (-7600 4425);
PAINT GREEN (-7600 4425);
DISPLAY INVISIBLE (-7600 4425);
FORCEPROP 1 LAST COMMENT_BODY TRUE
J 2
(-7230 4455);
DISPLAY 0.872340 (-7230 4455);
PAINT GREEN (-7230 4455);
DISPLAY INVISIBLE (-7230 4455);
FORCEPROP 2 LAST PATH I2005
J 0
(-7225 4625);
DISPLAY 0.680851 (-7225 4625);
DISPLAY INVISIBLE (-7225 4625);
FORCEADD OFFPAGE..2
R 2
(-7275 4450);
FORCEPROP 2 LAST $XR1 54 
J 0
(-7619 4450);
DISPLAY 0.638298 (-7619 4450);
PAINT MONO (-7619 4450);
FORCEPROP 2 LAST $XR0 82 
J 0
(-7529 4450);
DISPLAY 0.638298 (-7529 4450);
PAINT MONO (-7529 4450);
FORCEPROP 2 LAST CDS_LIB standard
J 0
(-7275 4450);
DISPLAY INVISIBLE (-7275 4450);
FORCEPROP 1 LAST OFFPAGE TRUE
J 2
(-7600 4325);
DISPLAY 0.872340 (-7600 4325);
PAINT GREEN (-7600 4325);
DISPLAY INVISIBLE (-7600 4325);
FORCEPROP 1 LAST COMMENT_BODY TRUE
J 2
(-7230 4355);
DISPLAY 0.872340 (-7230 4355);
PAINT GREEN (-7230 4355);
DISPLAY INVISIBLE (-7230 4355);
FORCEPROP 2 LAST PATH I2006
J 0
(-7225 4525);
DISPLAY 0.680851 (-7225 4525);
DISPLAY INVISIBLE (-7225 4525);
FORCEADD OFFPAGE..4
R 2
(-7275 4400);
FORCEPROP 2 LAST $XR1 115 
J 0
(-7646 4400);
DISPLAY 0.638298 (-7646 4400);
PAINT MONO (-7646 4400);
FORCEPROP 2 LAST $XR0 82 
J 0
(-7526 4400);
DISPLAY 0.638298 (-7526 4400);
PAINT MONO (-7526 4400);
FORCEPROP 2 LAST CDS_LIB standard
J 0
(-7275 4400);
DISPLAY INVISIBLE (-7275 4400);
FORCEPROP 1 LAST COMMENT_BODY TRUE
J 2
(-7250 4300);
DISPLAY 0.872340 (-7250 4300);
PAINT GREEN (-7250 4300);
DISPLAY INVISIBLE (-7250 4300);
FORCEPROP 1 LAST OFFPAGE TRUE
J 2
(-7600 4275);
DISPLAY 0.872340 (-7600 4275);
PAINT GREEN (-7600 4275);
DISPLAY INVISIBLE (-7600 4275);
FORCEPROP 2 LAST PATH I2007
J 0
(-7225 4475);
DISPLAY 0.680851 (-7225 4475);
DISPLAY INVISIBLE (-7225 4475);
FORCEADD OFFPAGE..2
R 2
(-7275 4350);
FORCEPROP 2 LAST $XR0 28 
J 0
(-7529 4350);
DISPLAY 0.638298 (-7529 4350);
PAINT MONO (-7529 4350);
FORCEPROP 2 LAST CDS_LIB standard
J 0
(-7275 4350);
DISPLAY INVISIBLE (-7275 4350);
FORCEPROP 1 LAST OFFPAGE TRUE
J 2
(-7600 4225);
DISPLAY 0.872340 (-7600 4225);
PAINT GREEN (-7600 4225);
DISPLAY INVISIBLE (-7600 4225);
FORCEPROP 1 LAST COMMENT_BODY TRUE
J 2
(-7230 4255);
DISPLAY 0.872340 (-7230 4255);
PAINT GREEN (-7230 4255);
DISPLAY INVISIBLE (-7230 4255);
FORCEPROP 2 LAST PATH I2008
J 0
(-7225 4425);
DISPLAY 0.680851 (-7225 4425);
DISPLAY INVISIBLE (-7225 4425);
FORCEADD OFFPAGE..4
R 2
(-7275 4250);
FORCEPROP 2 LAST $XR0 83 
J 0
(-7526 4250);
DISPLAY 0.638298 (-7526 4250);
PAINT MONO (-7526 4250);
FORCEPROP 2 LAST CDS_LIB standard
J 0
(-7275 4250);
DISPLAY INVISIBLE (-7275 4250);
FORCEPROP 1 LAST COMMENT_BODY TRUE
J 2
(-7250 4150);
DISPLAY 0.872340 (-7250 4150);
PAINT GREEN (-7250 4150);
DISPLAY INVISIBLE (-7250 4150);
FORCEPROP 1 LAST OFFPAGE TRUE
J 2
(-7600 4125);
DISPLAY 0.872340 (-7600 4125);
PAINT GREEN (-7600 4125);
DISPLAY INVISIBLE (-7600 4125);
FORCEPROP 2 LAST PATH I2009
J 0
(-7225 4325);
DISPLAY 0.680851 (-7225 4325);
DISPLAY INVISIBLE (-7225 4325);
FORCEADD OFFPAGE..2
R 2
(-7275 4300);
FORCEPROP 2 LAST $XR1 54 
J 0
(-7619 4300);
DISPLAY 0.638298 (-7619 4300);
PAINT MONO (-7619 4300);
FORCEPROP 2 LAST $XR0 82 
J 0
(-7529 4300);
DISPLAY 0.638298 (-7529 4300);
PAINT MONO (-7529 4300);
FORCEPROP 2 LAST CDS_LIB standard
J 0
(-7275 4300);
DISPLAY INVISIBLE (-7275 4300);
FORCEPROP 1 LAST OFFPAGE TRUE
J 2
(-7600 4175);
DISPLAY 0.872340 (-7600 4175);
PAINT GREEN (-7600 4175);
DISPLAY INVISIBLE (-7600 4175);
FORCEPROP 1 LAST COMMENT_BODY TRUE
J 2
(-7230 4205);
DISPLAY 0.872340 (-7230 4205);
PAINT GREEN (-7230 4205);
DISPLAY INVISIBLE (-7230 4205);
FORCEPROP 2 LAST PATH I2010
J 0
(-7225 4375);
DISPLAY 0.680851 (-7225 4375);
DISPLAY INVISIBLE (-7225 4375);
FORCEADD OFFPAGE..4
R 2
(-7275 4200);
FORCEPROP 2 LAST $XR0 83 
J 0
(-7496 4200);
DISPLAY 0.638298 (-7496 4200);
PAINT MONO (-7496 4200);
FORCEPROP 2 LAST CDS_LIB standard
J 0
(-7275 4200);
DISPLAY INVISIBLE (-7275 4200);
FORCEPROP 1 LAST COMMENT_BODY TRUE
J 2
(-7250 4100);
DISPLAY 0.872340 (-7250 4100);
PAINT GREEN (-7250 4100);
DISPLAY INVISIBLE (-7250 4100);
FORCEPROP 1 LAST OFFPAGE TRUE
J 2
(-7600 4075);
DISPLAY 0.872340 (-7600 4075);
PAINT GREEN (-7600 4075);
DISPLAY INVISIBLE (-7600 4075);
FORCEPROP 2 LAST PATH I2011
J 0
(-7225 4275);
DISPLAY 0.680851 (-7225 4275);
DISPLAY INVISIBLE (-7225 4275);
FORCEADD OFFPAGE..2
R 2
(-7275 4150);
FORCEPROP 2 LAST $XR1 27 
J 0
(-7619 4150);
DISPLAY 0.638298 (-7619 4150);
PAINT MONO (-7619 4150);
FORCEPROP 2 LAST $XR0 82 
J 0
(-7529 4150);
DISPLAY 0.638298 (-7529 4150);
PAINT MONO (-7529 4150);
FORCEPROP 2 LAST CDS_LIB standard
J 0
(-7275 4150);
DISPLAY INVISIBLE (-7275 4150);
FORCEPROP 1 LAST OFFPAGE TRUE
J 2
(-7600 4025);
DISPLAY 0.872340 (-7600 4025);
PAINT GREEN (-7600 4025);
DISPLAY INVISIBLE (-7600 4025);
FORCEPROP 1 LAST COMMENT_BODY TRUE
J 2
(-7230 4055);
DISPLAY 0.872340 (-7230 4055);
PAINT GREEN (-7230 4055);
DISPLAY INVISIBLE (-7230 4055);
FORCEPROP 2 LAST PATH I2012
J 0
(-7225 4225);
DISPLAY 0.680851 (-7225 4225);
DISPLAY INVISIBLE (-7225 4225);
FORCEADD OFFPAGE..2
R 2
(-7275 4100);
FORCEPROP 2 LAST $XR1 27 
J 0
(-7619 4100);
DISPLAY 0.638298 (-7619 4100);
PAINT MONO (-7619 4100);
FORCEPROP 2 LAST $XR0 82 
J 0
(-7529 4100);
DISPLAY 0.638298 (-7529 4100);
PAINT MONO (-7529 4100);
FORCEPROP 2 LAST CDS_LIB standard
J 0
(-7275 4100);
DISPLAY INVISIBLE (-7275 4100);
FORCEPROP 1 LAST OFFPAGE TRUE
J 2
(-7600 3975);
DISPLAY 0.872340 (-7600 3975);
PAINT GREEN (-7600 3975);
DISPLAY INVISIBLE (-7600 3975);
FORCEPROP 1 LAST COMMENT_BODY TRUE
J 2
(-7230 4005);
DISPLAY 0.872340 (-7230 4005);
PAINT GREEN (-7230 4005);
DISPLAY INVISIBLE (-7230 4005);
FORCEPROP 2 LAST PATH I2013
J 0
(-7225 4175);
DISPLAY 0.680851 (-7225 4175);
DISPLAY INVISIBLE (-7225 4175);
FORCEADD OFFPAGE..4
R 2
(-7275 4050);
FORCEPROP 2 LAST $XR0 54 
J 0
(-7526 4050);
DISPLAY 0.638298 (-7526 4050);
PAINT MONO (-7526 4050);
FORCEPROP 2 LAST CDS_LIB standard
J 0
(-7275 4050);
DISPLAY INVISIBLE (-7275 4050);
FORCEPROP 1 LAST COMMENT_BODY TRUE
J 2
(-7250 3950);
DISPLAY 0.872340 (-7250 3950);
PAINT GREEN (-7250 3950);
DISPLAY INVISIBLE (-7250 3950);
FORCEPROP 1 LAST OFFPAGE TRUE
J 2
(-7600 3925);
DISPLAY 0.872340 (-7600 3925);
PAINT GREEN (-7600 3925);
DISPLAY INVISIBLE (-7600 3925);
FORCEPROP 2 LAST PATH I2014
J 0
(-7225 4125);
DISPLAY 0.680851 (-7225 4125);
DISPLAY INVISIBLE (-7225 4125);
FORCEADD OFFPAGE..4
R 2
(-7275 4000);
FORCEPROP 2 LAST $XR0 27 
J 0
(-7496 4000);
DISPLAY 0.638298 (-7496 4000);
PAINT MONO (-7496 4000);
FORCEPROP 2 LAST CDS_LIB standard
J 0
(-7275 4000);
DISPLAY INVISIBLE (-7275 4000);
FORCEPROP 1 LAST COMMENT_BODY TRUE
J 2
(-7250 3900);
DISPLAY 0.872340 (-7250 3900);
PAINT GREEN (-7250 3900);
DISPLAY INVISIBLE (-7250 3900);
FORCEPROP 1 LAST OFFPAGE TRUE
J 2
(-7600 3875);
DISPLAY 0.872340 (-7600 3875);
PAINT GREEN (-7600 3875);
DISPLAY INVISIBLE (-7600 3875);
FORCEPROP 2 LAST PATH I2015
J 0
(-7225 4075);
DISPLAY 0.680851 (-7225 4075);
DISPLAY INVISIBLE (-7225 4075);
FORCEADD OFFPAGE..4
R 2
(-7275 3950);
FORCEPROP 2 LAST $XR0 55 
J 0
(-7496 3950);
DISPLAY 0.638298 (-7496 3950);
PAINT MONO (-7496 3950);
FORCEPROP 2 LAST CDS_LIB standard
J 0
(-7275 3950);
DISPLAY INVISIBLE (-7275 3950);
FORCEPROP 1 LAST COMMENT_BODY TRUE
J 2
(-7250 3850);
DISPLAY 0.872340 (-7250 3850);
PAINT GREEN (-7250 3850);
DISPLAY INVISIBLE (-7250 3850);
FORCEPROP 1 LAST OFFPAGE TRUE
J 2
(-7600 3825);
DISPLAY 0.872340 (-7600 3825);
PAINT GREEN (-7600 3825);
DISPLAY INVISIBLE (-7600 3825);
FORCEPROP 2 LAST PATH I2016
J 0
(-7225 4025);
DISPLAY 0.680851 (-7225 4025);
DISPLAY INVISIBLE (-7225 4025);
FORCEADD OFFPAGE..4
R 2
(-7275 3900);
FORCEPROP 2 LAST $XR1 162 
J 0
(-7616 3900);
DISPLAY 0.638298 (-7616 3900);
PAINT MONO (-7616 3900);
FORCEPROP 2 LAST $XR0 82 
J 0
(-7496 3900);
DISPLAY 0.638298 (-7496 3900);
PAINT MONO (-7496 3900);
FORCEPROP 2 LAST CDS_LIB standard
J 0
(-7275 3900);
DISPLAY INVISIBLE (-7275 3900);
FORCEPROP 1 LAST COMMENT_BODY TRUE
J 2
(-7250 3800);
DISPLAY 0.872340 (-7250 3800);
PAINT GREEN (-7250 3800);
DISPLAY INVISIBLE (-7250 3800);
FORCEPROP 1 LAST OFFPAGE TRUE
J 2
(-7600 3775);
DISPLAY 0.872340 (-7600 3775);
PAINT GREEN (-7600 3775);
DISPLAY INVISIBLE (-7600 3775);
FORCEPROP 2 LAST PATH I2017
J 0
(-7225 3975);
DISPLAY 0.680851 (-7225 3975);
DISPLAY INVISIBLE (-7225 3975);
FORCEADD OFFPAGE..4
R 2
(-7275 3800);
FORCEPROP 2 LAST $XR0 140 
J 0
(-7527 3800);
DISPLAY 0.638298 (-7527 3800);
PAINT MONO (-7527 3800);
FORCEPROP 2 LAST CDS_LIB standard
J 0
(-7275 3800);
DISPLAY INVISIBLE (-7275 3800);
FORCEPROP 1 LAST COMMENT_BODY TRUE
J 2
(-7250 3700);
DISPLAY 0.872340 (-7250 3700);
PAINT GREEN (-7250 3700);
DISPLAY INVISIBLE (-7250 3700);
FORCEPROP 1 LAST OFFPAGE TRUE
J 2
(-7600 3675);
DISPLAY 0.872340 (-7600 3675);
PAINT GREEN (-7600 3675);
DISPLAY INVISIBLE (-7600 3675);
FORCEPROP 2 LAST PATH I2018
J 0
(-7225 3875);
DISPLAY 0.680851 (-7225 3875);
DISPLAY INVISIBLE (-7225 3875);
FORCEADD OFFPAGE..4
R 2
(-7275 3850);
FORCEPROP 2 LAST $XR1 162 
J 0
(-7616 3850);
DISPLAY 0.638298 (-7616 3850);
PAINT MONO (-7616 3850);
FORCEPROP 2 LAST $XR0 82 
J 0
(-7496 3850);
DISPLAY 0.638298 (-7496 3850);
PAINT MONO (-7496 3850);
FORCEPROP 2 LAST CDS_LIB standard
J 0
(-7275 3850);
DISPLAY INVISIBLE (-7275 3850);
FORCEPROP 1 LAST COMMENT_BODY TRUE
J 2
(-7250 3750);
DISPLAY 0.872340 (-7250 3750);
PAINT GREEN (-7250 3750);
DISPLAY INVISIBLE (-7250 3750);
FORCEPROP 1 LAST OFFPAGE TRUE
J 2
(-7600 3725);
DISPLAY 0.872340 (-7600 3725);
PAINT GREEN (-7600 3725);
DISPLAY INVISIBLE (-7600 3725);
FORCEPROP 2 LAST PATH I2019
J 0
(-7225 3925);
DISPLAY 0.680851 (-7225 3925);
DISPLAY INVISIBLE (-7225 3925);
FORCEADD OFFPAGE..2
R 2
(-7275 3750);
FORCEPROP 2 LAST $XR0 83 
J 0
(-7529 3750);
DISPLAY 0.638298 (-7529 3750);
PAINT MONO (-7529 3750);
FORCEPROP 2 LAST CDS_LIB standard
J 0
(-7275 3750);
DISPLAY INVISIBLE (-7275 3750);
FORCEPROP 1 LAST OFFPAGE TRUE
J 2
(-7600 3625);
DISPLAY 0.872340 (-7600 3625);
PAINT GREEN (-7600 3625);
DISPLAY INVISIBLE (-7600 3625);
FORCEPROP 1 LAST COMMENT_BODY TRUE
J 2
(-7230 3655);
DISPLAY 0.872340 (-7230 3655);
PAINT GREEN (-7230 3655);
DISPLAY INVISIBLE (-7230 3655);
FORCEPROP 2 LAST PATH I2020
J 0
(-7225 3825);
DISPLAY 0.680851 (-7225 3825);
DISPLAY INVISIBLE (-7225 3825);
FORCEADD OFFPAGE..2
R 2
(-7275 3700);
FORCEPROP 2 LAST $XR0 83 
J 0
(-7529 3700);
DISPLAY 0.638298 (-7529 3700);
PAINT MONO (-7529 3700);
FORCEPROP 2 LAST CDS_LIB standard
J 0
(-7275 3700);
DISPLAY INVISIBLE (-7275 3700);
FORCEPROP 1 LAST OFFPAGE TRUE
J 2
(-7600 3575);
DISPLAY 0.872340 (-7600 3575);
PAINT GREEN (-7600 3575);
DISPLAY INVISIBLE (-7600 3575);
FORCEPROP 1 LAST COMMENT_BODY TRUE
J 2
(-7230 3605);
DISPLAY 0.872340 (-7230 3605);
PAINT GREEN (-7230 3605);
DISPLAY INVISIBLE (-7230 3605);
FORCEPROP 2 LAST PATH I2021
J 0
(-7225 3775);
DISPLAY 0.680851 (-7225 3775);
DISPLAY INVISIBLE (-7225 3775);
FORCEADD OFFPAGE..4
R 2
(-7275 3650);
FORCEPROP 2 LAST $XR0 160 
J 0
(-7557 3650);
DISPLAY 0.638298 (-7557 3650);
PAINT MONO (-7557 3650);
FORCEPROP 2 LAST CDS_LIB standard
J 0
(-7275 3650);
DISPLAY INVISIBLE (-7275 3650);
FORCEPROP 1 LAST COMMENT_BODY TRUE
J 2
(-7250 3550);
DISPLAY 0.872340 (-7250 3550);
PAINT GREEN (-7250 3550);
DISPLAY INVISIBLE (-7250 3550);
FORCEPROP 1 LAST OFFPAGE TRUE
J 2
(-7600 3525);
DISPLAY 0.872340 (-7600 3525);
PAINT GREEN (-7600 3525);
DISPLAY INVISIBLE (-7600 3525);
FORCEPROP 2 LAST PATH I2022
J 0
(-7225 3725);
DISPLAY 0.680851 (-7225 3725);
DISPLAY INVISIBLE (-7225 3725);
FORCEADD OFFPAGE..6
R 2
(-1375 2750);
FORCEPROP 2 LAST $XR0 158 
J 0
(-1161 2750);
DISPLAY 0.638298 (-1161 2750);
PAINT MONO (-1161 2750);
FORCEPROP 2 LAST PATH I2024
J 0
(-1150 2800);
DISPLAY 0.680851 (-1150 2800);
DISPLAY INVISIBLE (-1150 2800);
FORCEPROP 2 LAST CDS_LIB mstr_standard
J 0
(-1375 2750);
DISPLAY INVISIBLE (-1375 2750);
FORCEPROP 1 LAST OFFPAGE TRUE
J 2
(-1700 2625);
DISPLAY 0.872340 (-1700 2625);
PAINT GREEN (-1700 2625);
DISPLAY INVISIBLE (-1700 2625);
FORCEPROP 1 LAST COMMENT_BODY TRUE
J 2
(-1475 2675);
DISPLAY 0.872340 (-1475 2675);
PAINT GREEN (-1475 2675);
DISPLAY INVISIBLE (-1475 2675);
FORCEADD OFFPAGE..2
(-1375 2700);
FORCEPROP 2 LAST $XR1 206 
J 0
(-1066 2700);
DISPLAY 0.638298 (-1066 2700);
PAINT MONO (-1066 2700);
FORCEPROP 2 LAST $XR0 82 
J 0
(-1156 2700);
DISPLAY 0.638298 (-1156 2700);
PAINT MONO (-1156 2700);
FORCEPROP 2 LAST PATH I2025
J 0
(-1075 2750);
DISPLAY 0.680851 (-1075 2750);
DISPLAY INVISIBLE (-1075 2750);
FORCEPROP 2 LAST CDS_LIB standard
J 0
(-1375 2700);
DISPLAY INVISIBLE (-1375 2700);
FORCEPROP 1 LAST OFFPAGE TRUE
J 0
(-1050 2575);
DISPLAY 0.872340 (-1050 2575);
PAINT GREEN (-1050 2575);
DISPLAY INVISIBLE (-1050 2575);
FORCEPROP 1 LAST COMMENT_BODY TRUE
J 0
(-1420 2605);
DISPLAY 0.872340 (-1420 2605);
PAINT GREEN (-1420 2605);
DISPLAY INVISIBLE (-1420 2605);
FORCEADD OFFPAGE..2
(-1375 2600);
FORCEPROP 2 LAST $XR0 117 
J 0
(-1186 2600);
DISPLAY 0.638298 (-1186 2600);
PAINT MONO (-1186 2600);
FORCEPROP 2 LAST PATH I2026
J 0
(-1175 2650);
DISPLAY 0.680851 (-1175 2650);
DISPLAY INVISIBLE (-1175 2650);
FORCEPROP 2 LAST CDS_LIB standard
J 0
(-1375 2600);
DISPLAY INVISIBLE (-1375 2600);
FORCEPROP 1 LAST OFFPAGE TRUE
J 0
(-1050 2475);
DISPLAY 0.872340 (-1050 2475);
PAINT GREEN (-1050 2475);
DISPLAY INVISIBLE (-1050 2475);
FORCEPROP 1 LAST COMMENT_BODY TRUE
J 0
(-1420 2505);
DISPLAY 0.872340 (-1420 2505);
PAINT GREEN (-1420 2505);
DISPLAY INVISIBLE (-1420 2505);
FORCEADD OFFPAGE..2
(-1375 2550);
FORCEPROP 2 LAST $XR1 124 
J 0
(-1096 2550);
DISPLAY 0.638298 (-1096 2550);
PAINT MONO (-1096 2550);
FORCEPROP 2 LAST $XR0 82 
J 0
(-1186 2550);
DISPLAY 0.638298 (-1186 2550);
PAINT MONO (-1186 2550);
FORCEPROP 2 LAST PATH I2027
J 0
(-1075 2600);
DISPLAY 0.680851 (-1075 2600);
DISPLAY INVISIBLE (-1075 2600);
FORCEPROP 2 LAST CDS_LIB standard
J 0
(-1375 2550);
DISPLAY INVISIBLE (-1375 2550);
FORCEPROP 1 LAST OFFPAGE TRUE
J 0
(-1050 2425);
DISPLAY 0.872340 (-1050 2425);
PAINT GREEN (-1050 2425);
DISPLAY INVISIBLE (-1050 2425);
FORCEPROP 1 LAST COMMENT_BODY TRUE
J 0
(-1420 2455);
DISPLAY 0.872340 (-1420 2455);
PAINT GREEN (-1420 2455);
DISPLAY INVISIBLE (-1420 2455);
FORCEADD OFFPAGE..2
(-1375 2500);
FORCEPROP 2 LAST $XR1 207 
J 0
(-1096 2500);
DISPLAY 0.638298 (-1096 2500);
PAINT MONO (-1096 2500);
FORCEPROP 2 LAST $XR0 82 
J 0
(-1186 2500);
DISPLAY 0.638298 (-1186 2500);
PAINT MONO (-1186 2500);
FORCEPROP 2 LAST PATH I2028
J 0
(-1075 2550);
DISPLAY 0.680851 (-1075 2550);
DISPLAY INVISIBLE (-1075 2550);
FORCEPROP 2 LAST CDS_LIB standard
J 0
(-1375 2500);
DISPLAY INVISIBLE (-1375 2500);
FORCEPROP 1 LAST OFFPAGE TRUE
J 0
(-1050 2375);
DISPLAY 0.872340 (-1050 2375);
PAINT GREEN (-1050 2375);
DISPLAY INVISIBLE (-1050 2375);
FORCEPROP 1 LAST COMMENT_BODY TRUE
J 0
(-1420 2405);
DISPLAY 0.872340 (-1420 2405);
PAINT GREEN (-1420 2405);
DISPLAY INVISIBLE (-1420 2405);
FORCEADD OFFPAGE..2
(-1375 2450);
FORCEPROP 2 LAST $XR1 208 
J 0
(-1096 2450);
DISPLAY 0.638298 (-1096 2450);
PAINT MONO (-1096 2450);
FORCEPROP 2 LAST $XR0 82 
J 0
(-1186 2450);
DISPLAY 0.638298 (-1186 2450);
PAINT MONO (-1186 2450);
FORCEPROP 2 LAST PATH I2029
J 0
(-1075 2500);
DISPLAY 0.680851 (-1075 2500);
DISPLAY INVISIBLE (-1075 2500);
FORCEPROP 2 LAST CDS_LIB standard
J 0
(-1375 2450);
DISPLAY INVISIBLE (-1375 2450);
FORCEPROP 1 LAST OFFPAGE TRUE
J 0
(-1050 2325);
DISPLAY 0.872340 (-1050 2325);
PAINT GREEN (-1050 2325);
DISPLAY INVISIBLE (-1050 2325);
FORCEPROP 1 LAST COMMENT_BODY TRUE
J 0
(-1420 2355);
DISPLAY 0.872340 (-1420 2355);
PAINT GREEN (-1420 2355);
DISPLAY INVISIBLE (-1420 2355);
FORCEADD OFFPAGE..2
(-1375 2400);
FORCEPROP 2 LAST $XR0 160 
J 0
(-1186 2400);
DISPLAY 0.638298 (-1186 2400);
PAINT MONO (-1186 2400);
FORCEPROP 2 LAST PATH I2030
J 0
(-1175 2450);
DISPLAY 0.680851 (-1175 2450);
DISPLAY INVISIBLE (-1175 2450);
FORCEPROP 2 LAST CDS_LIB standard
J 0
(-1375 2400);
DISPLAY INVISIBLE (-1375 2400);
FORCEPROP 1 LAST OFFPAGE TRUE
J 0
(-1050 2275);
DISPLAY 0.872340 (-1050 2275);
PAINT GREEN (-1050 2275);
DISPLAY INVISIBLE (-1050 2275);
FORCEPROP 1 LAST COMMENT_BODY TRUE
J 0
(-1420 2305);
DISPLAY 0.872340 (-1420 2305);
PAINT GREEN (-1420 2305);
DISPLAY INVISIBLE (-1420 2305);
FORCEADD OFFPAGE..2
(-1375 2350);
FORCEPROP 2 LAST $XR1 114 
J 0
(-1096 2350);
DISPLAY 0.638298 (-1096 2350);
PAINT MONO (-1096 2350);
FORCEPROP 2 LAST $XR0 82 
J 0
(-1186 2350);
DISPLAY 0.638298 (-1186 2350);
PAINT MONO (-1186 2350);
FORCEPROP 2 LAST PATH I2031
J 0
(-1075 2400);
DISPLAY 0.680851 (-1075 2400);
DISPLAY INVISIBLE (-1075 2400);
FORCEPROP 2 LAST CDS_LIB standard
J 0
(-1375 2350);
DISPLAY INVISIBLE (-1375 2350);
FORCEPROP 1 LAST OFFPAGE TRUE
J 0
(-1050 2225);
DISPLAY 0.872340 (-1050 2225);
PAINT GREEN (-1050 2225);
DISPLAY INVISIBLE (-1050 2225);
FORCEPROP 1 LAST COMMENT_BODY TRUE
J 0
(-1420 2255);
DISPLAY 0.872340 (-1420 2255);
PAINT GREEN (-1420 2255);
DISPLAY INVISIBLE (-1420 2255);
FORCEADD OFFPAGE..2
(-1375 2300);
FORCEPROP 2 LAST $XR1 126 
J 0
(-1096 2300);
DISPLAY 0.638298 (-1096 2300);
PAINT MONO (-1096 2300);
FORCEPROP 2 LAST $XR0 82 
J 0
(-1186 2300);
DISPLAY 0.638298 (-1186 2300);
PAINT MONO (-1186 2300);
FORCEPROP 2 LAST PATH I2032
J 0
(-1075 2350);
DISPLAY 0.680851 (-1075 2350);
DISPLAY INVISIBLE (-1075 2350);
FORCEPROP 2 LAST CDS_LIB standard
J 0
(-1375 2300);
DISPLAY INVISIBLE (-1375 2300);
FORCEPROP 1 LAST OFFPAGE TRUE
J 0
(-1050 2175);
DISPLAY 0.872340 (-1050 2175);
PAINT GREEN (-1050 2175);
DISPLAY INVISIBLE (-1050 2175);
FORCEPROP 1 LAST COMMENT_BODY TRUE
J 0
(-1420 2205);
DISPLAY 0.872340 (-1420 2205);
PAINT GREEN (-1420 2205);
DISPLAY INVISIBLE (-1420 2205);
FORCEADD OFFPAGE..2
(-1375 2250);
FORCEPROP 2 LAST $XR1 125 
J 0
(-1096 2250);
DISPLAY 0.638298 (-1096 2250);
PAINT MONO (-1096 2250);
FORCEPROP 2 LAST $XR0 82 
J 0
(-1186 2250);
DISPLAY 0.638298 (-1186 2250);
PAINT MONO (-1186 2250);
FORCEPROP 2 LAST PATH I2033
J 0
(-1075 2300);
DISPLAY 0.680851 (-1075 2300);
DISPLAY INVISIBLE (-1075 2300);
FORCEPROP 2 LAST CDS_LIB standard
J 0
(-1375 2250);
DISPLAY INVISIBLE (-1375 2250);
FORCEPROP 1 LAST OFFPAGE TRUE
J 0
(-1050 2125);
DISPLAY 0.872340 (-1050 2125);
PAINT GREEN (-1050 2125);
DISPLAY INVISIBLE (-1050 2125);
FORCEPROP 1 LAST COMMENT_BODY TRUE
J 0
(-1420 2155);
DISPLAY 0.872340 (-1420 2155);
PAINT GREEN (-1420 2155);
DISPLAY INVISIBLE (-1420 2155);
FORCEADD OFFPAGE..2
(-1375 2200);
FORCEPROP 2 LAST $XR1 131 
J 0
(-1096 2200);
DISPLAY 0.638298 (-1096 2200);
PAINT MONO (-1096 2200);
FORCEPROP 2 LAST $XR0 82 
J 0
(-1186 2200);
DISPLAY 0.638298 (-1186 2200);
PAINT MONO (-1186 2200);
FORCEPROP 2 LAST PATH I2034
J 0
(-1075 2250);
DISPLAY 0.680851 (-1075 2250);
DISPLAY INVISIBLE (-1075 2250);
FORCEPROP 2 LAST CDS_LIB standard
J 0
(-1375 2200);
DISPLAY INVISIBLE (-1375 2200);
FORCEPROP 1 LAST OFFPAGE TRUE
J 0
(-1050 2075);
DISPLAY 0.872340 (-1050 2075);
PAINT GREEN (-1050 2075);
DISPLAY INVISIBLE (-1050 2075);
FORCEPROP 1 LAST COMMENT_BODY TRUE
J 0
(-1420 2105);
DISPLAY 0.872340 (-1420 2105);
PAINT GREEN (-1420 2105);
DISPLAY INVISIBLE (-1420 2105);
FORCEADD OFFPAGE..2
(-1375 2150);
FORCEPROP 2 LAST $XR1 131 
J 0
(-1096 2150);
DISPLAY 0.638298 (-1096 2150);
PAINT MONO (-1096 2150);
FORCEPROP 2 LAST $XR0 82 
J 0
(-1186 2150);
DISPLAY 0.638298 (-1186 2150);
PAINT MONO (-1186 2150);
FORCEPROP 2 LAST PATH I2035
J 0
(-1075 2200);
DISPLAY 0.680851 (-1075 2200);
DISPLAY INVISIBLE (-1075 2200);
FORCEPROP 2 LAST CDS_LIB standard
J 0
(-1375 2150);
DISPLAY INVISIBLE (-1375 2150);
FORCEPROP 1 LAST OFFPAGE TRUE
J 0
(-1050 2025);
DISPLAY 0.872340 (-1050 2025);
PAINT GREEN (-1050 2025);
DISPLAY INVISIBLE (-1050 2025);
FORCEPROP 1 LAST COMMENT_BODY TRUE
J 0
(-1420 2055);
DISPLAY 0.872340 (-1420 2055);
PAINT GREEN (-1420 2055);
DISPLAY INVISIBLE (-1420 2055);
FORCEADD OFFPAGE..2
(-1375 2100);
FORCEPROP 2 LAST $XR1 207 
J 0
(-1096 2100);
DISPLAY 0.638298 (-1096 2100);
PAINT MONO (-1096 2100);
FORCEPROP 2 LAST $XR0 82 
J 0
(-1186 2100);
DISPLAY 0.638298 (-1186 2100);
PAINT MONO (-1186 2100);
FORCEPROP 2 LAST PATH I2036
J 0
(-1075 2150);
DISPLAY 0.680851 (-1075 2150);
DISPLAY INVISIBLE (-1075 2150);
FORCEPROP 2 LAST CDS_LIB standard
J 0
(-1375 2100);
DISPLAY INVISIBLE (-1375 2100);
FORCEPROP 1 LAST OFFPAGE TRUE
J 0
(-1050 1975);
DISPLAY 0.872340 (-1050 1975);
PAINT GREEN (-1050 1975);
DISPLAY INVISIBLE (-1050 1975);
FORCEPROP 1 LAST COMMENT_BODY TRUE
J 0
(-1420 2005);
DISPLAY 0.872340 (-1420 2005);
PAINT GREEN (-1420 2005);
DISPLAY INVISIBLE (-1420 2005);
FORCEADD OFFPAGE..2
(-1375 2050);
FORCEPROP 2 LAST $XR1 208 
J 0
(-1096 2050);
DISPLAY 0.638298 (-1096 2050);
PAINT MONO (-1096 2050);
FORCEPROP 2 LAST $XR0 82 
J 0
(-1186 2050);
DISPLAY 0.638298 (-1186 2050);
PAINT MONO (-1186 2050);
FORCEPROP 2 LAST PATH I2037
J 0
(-1075 2100);
DISPLAY 0.680851 (-1075 2100);
DISPLAY INVISIBLE (-1075 2100);
FORCEPROP 2 LAST CDS_LIB standard
J 0
(-1375 2050);
DISPLAY INVISIBLE (-1375 2050);
FORCEPROP 1 LAST OFFPAGE TRUE
J 0
(-1050 1925);
DISPLAY 0.872340 (-1050 1925);
PAINT GREEN (-1050 1925);
DISPLAY INVISIBLE (-1050 1925);
FORCEPROP 1 LAST COMMENT_BODY TRUE
J 0
(-1420 1955);
DISPLAY 0.872340 (-1420 1955);
PAINT GREEN (-1420 1955);
DISPLAY INVISIBLE (-1420 1955);
FORCEADD OFFPAGE..1
R 2
(-1375 2000);
FORCEPROP 2 LAST $XR0 208 
J 0
(-1189 2000);
DISPLAY 0.638298 (-1189 2000);
PAINT MONO (-1189 2000);
FORCEPROP 2 LAST CDS_LIB standard
J 0
(-1375 2000);
DISPLAY INVISIBLE (-1375 2000);
FORCEPROP 2 LAST PATH I2038
J 0
(-1175 2050);
DISPLAY 0.680851 (-1175 2050);
DISPLAY INVISIBLE (-1175 2050);
FORCEPROP 1 LAST COMMENT_BODY TRUE
J 2
(-1500 1900);
DISPLAY 0.872340 (-1500 1900);
PAINT GREEN (-1500 1900);
DISPLAY INVISIBLE (-1500 1900);
FORCEPROP 1 LAST OFFPAGE TRUE
J 2
(-1700 1875);
DISPLAY 0.872340 (-1700 1875);
PAINT GREEN (-1700 1875);
DISPLAY INVISIBLE (-1700 1875);
FORCEADD OFFPAGE..2
(-1375 1900);
FORCEPROP 2 LAST $XR0 126 
J 0
(-1186 1900);
DISPLAY 0.638298 (-1186 1900);
PAINT MONO (-1186 1900);
FORCEPROP 2 LAST PATH I2039
J 0
(-1175 1950);
DISPLAY 0.680851 (-1175 1950);
DISPLAY INVISIBLE (-1175 1950);
FORCEPROP 2 LAST CDS_LIB standard
J 0
(-1375 1900);
DISPLAY INVISIBLE (-1375 1900);
FORCEPROP 1 LAST OFFPAGE TRUE
J 0
(-1050 1775);
DISPLAY 0.872340 (-1050 1775);
PAINT GREEN (-1050 1775);
DISPLAY INVISIBLE (-1050 1775);
FORCEPROP 1 LAST COMMENT_BODY TRUE
J 0
(-1420 1805);
DISPLAY 0.872340 (-1420 1805);
PAINT GREEN (-1420 1805);
DISPLAY INVISIBLE (-1420 1805);
FORCEADD OFFPAGE..1
R 2
(-1375 1950);
FORCEPROP 2 LAST $XR1 127 
J 0
(-1069 1950);
DISPLAY 0.638298 (-1069 1950);
PAINT MONO (-1069 1950);
FORCEPROP 2 LAST $XR0 208 
J 0
(-1189 1950);
DISPLAY 0.638298 (-1189 1950);
PAINT MONO (-1189 1950);
FORCEPROP 2 LAST CDS_LIB standard
J 0
(-1375 1950);
DISPLAY INVISIBLE (-1375 1950);
FORCEPROP 2 LAST PATH I2040
J 0
(-1050 2000);
DISPLAY 0.680851 (-1050 2000);
DISPLAY INVISIBLE (-1050 2000);
FORCEPROP 1 LAST COMMENT_BODY TRUE
J 2
(-1500 1850);
DISPLAY 0.872340 (-1500 1850);
PAINT GREEN (-1500 1850);
DISPLAY INVISIBLE (-1500 1850);
FORCEPROP 1 LAST OFFPAGE TRUE
J 2
(-1700 1825);
DISPLAY 0.872340 (-1700 1825);
PAINT GREEN (-1700 1825);
DISPLAY INVISIBLE (-1700 1825);
FORCEADD OFFPAGE..2
(-1375 1850);
FORCEPROP 2 LAST $XR0 127 
J 0
(-1186 1850);
DISPLAY 0.638298 (-1186 1850);
PAINT MONO (-1186 1850);
FORCEPROP 2 LAST PATH I2041
J 0
(-1175 1900);
DISPLAY 0.680851 (-1175 1900);
DISPLAY INVISIBLE (-1175 1900);
FORCEPROP 2 LAST CDS_LIB standard
J 0
(-1375 1850);
DISPLAY INVISIBLE (-1375 1850);
FORCEPROP 1 LAST OFFPAGE TRUE
J 0
(-1050 1725);
DISPLAY 0.872340 (-1050 1725);
PAINT GREEN (-1050 1725);
DISPLAY INVISIBLE (-1050 1725);
FORCEPROP 1 LAST COMMENT_BODY TRUE
J 0
(-1420 1755);
DISPLAY 0.872340 (-1420 1755);
PAINT GREEN (-1420 1755);
DISPLAY INVISIBLE (-1420 1755);
FORCEADD OFFPAGE..2
(-1375 1800);
FORCEPROP 2 LAST $XR0 159 
J 0
(-1186 1800);
DISPLAY 0.638298 (-1186 1800);
PAINT MONO (-1186 1800);
FORCEPROP 2 LAST PATH I2042
J 0
(-1150 1850);
DISPLAY 0.680851 (-1150 1850);
DISPLAY INVISIBLE (-1150 1850);
FORCEPROP 2 LAST CDS_LIB standard
J 0
(-1375 1800);
DISPLAY INVISIBLE (-1375 1800);
FORCEPROP 1 LAST OFFPAGE TRUE
J 0
(-1050 1675);
DISPLAY 0.872340 (-1050 1675);
PAINT GREEN (-1050 1675);
DISPLAY INVISIBLE (-1050 1675);
FORCEPROP 1 LAST COMMENT_BODY TRUE
J 0
(-1420 1705);
DISPLAY 0.872340 (-1420 1705);
PAINT GREEN (-1420 1705);
DISPLAY INVISIBLE (-1420 1705);
FORCEADD OFFPAGE..2
(-1375 1750);
FORCEPROP 2 LAST $XR0 161 
J 0
(-1186 1750);
DISPLAY 0.638298 (-1186 1750);
PAINT MONO (-1186 1750);
FORCEPROP 2 LAST PATH I2043
J 0
(-1175 1800);
DISPLAY 0.680851 (-1175 1800);
DISPLAY INVISIBLE (-1175 1800);
FORCEPROP 2 LAST CDS_LIB standard
J 0
(-1375 1750);
DISPLAY INVISIBLE (-1375 1750);
FORCEPROP 1 LAST OFFPAGE TRUE
J 0
(-1050 1625);
DISPLAY 0.872340 (-1050 1625);
PAINT GREEN (-1050 1625);
DISPLAY INVISIBLE (-1050 1625);
FORCEPROP 1 LAST COMMENT_BODY TRUE
J 0
(-1420 1655);
DISPLAY 0.872340 (-1420 1655);
PAINT GREEN (-1420 1655);
DISPLAY INVISIBLE (-1420 1655);
FORCEADD OFFPAGE..2
(-1375 1700);
FORCEPROP 2 LAST $XR1 127 
J 0
(-1096 1700);
DISPLAY 0.638298 (-1096 1700);
PAINT MONO (-1096 1700);
FORCEPROP 2 LAST $XR0 82 
J 0
(-1186 1700);
DISPLAY 0.638298 (-1186 1700);
PAINT MONO (-1186 1700);
FORCEPROP 2 LAST PATH I2044
J 0
(-1075 1750);
DISPLAY 0.680851 (-1075 1750);
DISPLAY INVISIBLE (-1075 1750);
FORCEPROP 2 LAST CDS_LIB standard
J 0
(-1375 1700);
DISPLAY INVISIBLE (-1375 1700);
FORCEPROP 1 LAST OFFPAGE TRUE
J 0
(-1050 1575);
DISPLAY 0.872340 (-1050 1575);
PAINT GREEN (-1050 1575);
DISPLAY INVISIBLE (-1050 1575);
FORCEPROP 1 LAST COMMENT_BODY TRUE
J 0
(-1420 1605);
DISPLAY 0.872340 (-1420 1605);
PAINT GREEN (-1420 1605);
DISPLAY INVISIBLE (-1420 1605);
FORCEADD OFFPAGE..2
(-1375 1650);
FORCEPROP 2 LAST $XR1 115 
J 0
(-1096 1650);
DISPLAY 0.638298 (-1096 1650);
PAINT MONO (-1096 1650);
FORCEPROP 2 LAST $XR0 82 
J 0
(-1186 1650);
DISPLAY 0.638298 (-1186 1650);
PAINT MONO (-1186 1650);
FORCEPROP 2 LAST PATH I2045
J 0
(-1075 1700);
DISPLAY 0.680851 (-1075 1700);
DISPLAY INVISIBLE (-1075 1700);
FORCEPROP 2 LAST CDS_LIB standard
J 0
(-1375 1650);
DISPLAY INVISIBLE (-1375 1650);
FORCEPROP 1 LAST OFFPAGE TRUE
J 0
(-1050 1525);
DISPLAY 0.872340 (-1050 1525);
PAINT GREEN (-1050 1525);
DISPLAY INVISIBLE (-1050 1525);
FORCEPROP 1 LAST COMMENT_BODY TRUE
J 0
(-1420 1555);
DISPLAY 0.872340 (-1420 1555);
PAINT GREEN (-1420 1555);
DISPLAY INVISIBLE (-1420 1555);
FORCEADD OFFPAGE..2
(-1375 1500);
FORCEPROP 2 LAST $XR0 161 
J 0
(-1186 1500);
DISPLAY 0.638298 (-1186 1500);
PAINT MONO (-1186 1500);
FORCEPROP 1 LAST OFFPAGE TRUE
J 0
(-1050 1375);
DISPLAY 0.872340 (-1050 1375);
PAINT GREEN (-1050 1375);
DISPLAY INVISIBLE (-1050 1375);
FORCEPROP 1 LAST COMMENT_BODY TRUE
J 0
(-1420 1405);
DISPLAY 0.872340 (-1420 1405);
PAINT GREEN (-1420 1405);
DISPLAY INVISIBLE (-1420 1405);
FORCEPROP 2 LAST PATH I2046
J 0
(-1175 1550);
DISPLAY 0.680851 (-1175 1550);
DISPLAY INVISIBLE (-1175 1550);
FORCEPROP 2 LAST CDS_LIB standard
J 0
(-1375 1500);
DISPLAY INVISIBLE (-1375 1500);
FORCEADD OFFPAGE..2
(-1375 1450);
FORCEPROP 2 LAST $XR1 128 
J 0
(-1096 1450);
DISPLAY 0.638298 (-1096 1450);
PAINT MONO (-1096 1450);
FORCEPROP 2 LAST $XR0 82 
J 0
(-1186 1450);
DISPLAY 0.638298 (-1186 1450);
PAINT MONO (-1186 1450);
FORCEPROP 2 LAST PATH I2047
J 0
(-1075 1500);
DISPLAY 0.680851 (-1075 1500);
DISPLAY INVISIBLE (-1075 1500);
FORCEPROP 2 LAST CDS_LIB standard
J 0
(-1375 1450);
DISPLAY INVISIBLE (-1375 1450);
FORCEPROP 1 LAST OFFPAGE TRUE
J 0
(-1050 1325);
DISPLAY 0.872340 (-1050 1325);
PAINT GREEN (-1050 1325);
DISPLAY INVISIBLE (-1050 1325);
FORCEPROP 1 LAST COMMENT_BODY TRUE
J 0
(-1420 1355);
DISPLAY 0.872340 (-1420 1355);
PAINT GREEN (-1420 1355);
DISPLAY INVISIBLE (-1420 1355);
FORCEADD OFFPAGE..2
(-1375 1300);
FORCEPROP 2 LAST $XR1 128 
J 0
(-1096 1300);
DISPLAY 0.638298 (-1096 1300);
PAINT MONO (-1096 1300);
FORCEPROP 2 LAST $XR0 82 
J 0
(-1186 1300);
DISPLAY 0.638298 (-1186 1300);
PAINT MONO (-1186 1300);
FORCEPROP 2 LAST PATH I2048
J 0
(-1075 1350);
DISPLAY 0.680851 (-1075 1350);
DISPLAY INVISIBLE (-1075 1350);
FORCEPROP 2 LAST CDS_LIB standard
J 0
(-1375 1300);
DISPLAY INVISIBLE (-1375 1300);
FORCEPROP 1 LAST OFFPAGE TRUE
J 0
(-1050 1175);
DISPLAY 0.872340 (-1050 1175);
PAINT GREEN (-1050 1175);
DISPLAY INVISIBLE (-1050 1175);
FORCEPROP 1 LAST COMMENT_BODY TRUE
J 0
(-1420 1205);
DISPLAY 0.872340 (-1420 1205);
PAINT GREEN (-1420 1205);
DISPLAY INVISIBLE (-1420 1205);
FORCEADD OFFPAGE..2
(-1375 1250);
FORCEPROP 2 LAST $XR0 84 
J 0
(-1186 1250);
DISPLAY 0.638298 (-1186 1250);
PAINT MONO (-1186 1250);
FORCEPROP 2 LAST PATH I2049
J 0
(-1175 1300);
DISPLAY 0.680851 (-1175 1300);
DISPLAY INVISIBLE (-1175 1300);
FORCEPROP 2 LAST CDS_LIB standard
J 0
(-1375 1250);
DISPLAY INVISIBLE (-1375 1250);
FORCEPROP 1 LAST OFFPAGE TRUE
J 0
(-1050 1125);
DISPLAY 0.872340 (-1050 1125);
PAINT GREEN (-1050 1125);
DISPLAY INVISIBLE (-1050 1125);
FORCEPROP 1 LAST COMMENT_BODY TRUE
J 0
(-1420 1155);
DISPLAY 0.872340 (-1420 1155);
PAINT GREEN (-1420 1155);
DISPLAY INVISIBLE (-1420 1155);
FORCEADD OFFPAGE..2
(-1375 1200);
FORCEPROP 2 LAST $XR1 116 
J 0
(-1096 1200);
DISPLAY 0.638298 (-1096 1200);
PAINT MONO (-1096 1200);
FORCEPROP 2 LAST $XR0 82 
J 0
(-1186 1200);
DISPLAY 0.638298 (-1186 1200);
PAINT MONO (-1186 1200);
FORCEPROP 2 LAST PATH I2050
J 0
(-1075 1250);
DISPLAY 0.680851 (-1075 1250);
DISPLAY INVISIBLE (-1075 1250);
FORCEPROP 2 LAST CDS_LIB standard
J 0
(-1375 1200);
DISPLAY INVISIBLE (-1375 1200);
FORCEPROP 1 LAST OFFPAGE TRUE
J 0
(-1050 1075);
DISPLAY 0.872340 (-1050 1075);
PAINT GREEN (-1050 1075);
DISPLAY INVISIBLE (-1050 1075);
FORCEPROP 1 LAST COMMENT_BODY TRUE
J 0
(-1420 1105);
DISPLAY 0.872340 (-1420 1105);
PAINT GREEN (-1420 1105);
DISPLAY INVISIBLE (-1420 1105);
FORCEADD OFFPAGE..2
(-1375 1100);
FORCEPROP 2 LAST $XR0 153 
J 0
(-1186 1100);
DISPLAY 0.638298 (-1186 1100);
PAINT MONO (-1186 1100);
FORCEPROP 2 LAST PATH I2051
J 0
(-1175 1150);
DISPLAY 0.680851 (-1175 1150);
DISPLAY INVISIBLE (-1175 1150);
FORCEPROP 2 LAST CDS_LIB standard
J 0
(-1375 1100);
DISPLAY INVISIBLE (-1375 1100);
FORCEPROP 1 LAST OFFPAGE TRUE
J 0
(-1050 975);
DISPLAY 0.872340 (-1050 975);
PAINT GREEN (-1050 975);
DISPLAY INVISIBLE (-1050 975);
FORCEPROP 1 LAST COMMENT_BODY TRUE
J 0
(-1420 1005);
DISPLAY 0.872340 (-1420 1005);
PAINT GREEN (-1420 1005);
DISPLAY INVISIBLE (-1420 1005);
FORCEADD OFFPAGE..2
(-1375 900);
FORCEPROP 2 LAST $XR1 115 
J 0
(-1096 900);
DISPLAY 0.638298 (-1096 900);
PAINT MONO (-1096 900);
FORCEPROP 2 LAST $XR0 82 
J 0
(-1186 900);
DISPLAY 0.638298 (-1186 900);
PAINT MONO (-1186 900);
FORCEPROP 2 LAST PATH I2052
J 0
(-1075 950);
DISPLAY 0.680851 (-1075 950);
DISPLAY INVISIBLE (-1075 950);
FORCEPROP 2 LAST CDS_LIB standard
J 0
(-1375 900);
DISPLAY INVISIBLE (-1375 900);
FORCEPROP 1 LAST OFFPAGE TRUE
J 0
(-1050 775);
DISPLAY 0.872340 (-1050 775);
PAINT GREEN (-1050 775);
DISPLAY INVISIBLE (-1050 775);
FORCEPROP 1 LAST COMMENT_BODY TRUE
J 0
(-1420 805);
DISPLAY 0.872340 (-1420 805);
PAINT GREEN (-1420 805);
DISPLAY INVISIBLE (-1420 805);
FORCEADD OFFPAGE..2
(-1375 850);
FORCEPROP 2 LAST $XR1 114 
J 0
(-1096 850);
DISPLAY 0.638298 (-1096 850);
PAINT MONO (-1096 850);
FORCEPROP 2 LAST $XR0 82 
J 0
(-1186 850);
DISPLAY 0.638298 (-1186 850);
PAINT MONO (-1186 850);
FORCEPROP 2 LAST PATH I2053
J 0
(-1075 900);
DISPLAY 0.680851 (-1075 900);
DISPLAY INVISIBLE (-1075 900);
FORCEPROP 2 LAST CDS_LIB standard
J 0
(-1375 850);
DISPLAY INVISIBLE (-1375 850);
FORCEPROP 1 LAST OFFPAGE TRUE
J 0
(-1050 725);
DISPLAY 0.872340 (-1050 725);
PAINT GREEN (-1050 725);
DISPLAY INVISIBLE (-1050 725);
FORCEPROP 1 LAST COMMENT_BODY TRUE
J 0
(-1420 755);
DISPLAY 0.872340 (-1420 755);
PAINT GREEN (-1420 755);
DISPLAY INVISIBLE (-1420 755);
FORCEADD OFFPAGE..1
R 2
(-1375 800);
FORCEPROP 2 LAST $XR1 118 
J 0
(-1069 800);
DISPLAY 0.638298 (-1069 800);
PAINT MONO (-1069 800);
FORCEPROP 2 LAST $XR0 117 
J 0
(-1189 800);
DISPLAY 0.638298 (-1189 800);
PAINT MONO (-1189 800);
FORCEPROP 2 LAST PATH I2054
J 0
(-1050 850);
DISPLAY 0.680851 (-1050 850);
DISPLAY INVISIBLE (-1050 850);
FORCEPROP 2 LAST CDS_LIB standard
J 0
(-1375 800);
DISPLAY INVISIBLE (-1375 800);
FORCEPROP 1 LAST OFFPAGE TRUE
J 2
(-1700 675);
DISPLAY 0.872340 (-1700 675);
PAINT GREEN (-1700 675);
DISPLAY INVISIBLE (-1700 675);
FORCEPROP 1 LAST COMMENT_BODY TRUE
J 2
(-1500 700);
DISPLAY 0.872340 (-1500 700);
PAINT GREEN (-1500 700);
DISPLAY INVISIBLE (-1500 700);
FORCEADD OFFPAGE..3
(-1375 750);
FORCEPROP 2 LAST $XR0 117 
J 0
(-1161 750);
DISPLAY 0.638298 (-1161 750);
PAINT MONO (-1161 750);
FORCEPROP 2 LAST PATH I2055
J 0
(-1150 800);
DISPLAY 0.680851 (-1150 800);
DISPLAY INVISIBLE (-1150 800);
FORCEPROP 2 LAST CDS_LIB standard
J 0
(-1375 750);
DISPLAY INVISIBLE (-1375 750);
FORCEPROP 1 LAST OFFPAGE TRUE
J 0
(-1050 625);
DISPLAY 0.872340 (-1050 625);
PAINT GREEN (-1050 625);
DISPLAY INVISIBLE (-1050 625);
FORCEPROP 1 LAST COMMENT_BODY TRUE
J 0
(-1425 650);
DISPLAY 0.872340 (-1425 650);
PAINT GREEN (-1425 650);
DISPLAY INVISIBLE (-1425 650);
FORCEADD OFFPAGE..2
(-1375 650);
FORCEPROP 2 LAST $XR0 154 
J 0
(-1186 650);
DISPLAY 0.638298 (-1186 650);
PAINT MONO (-1186 650);
FORCEPROP 2 LAST PATH I2056
J 0
(-1150 700);
DISPLAY 0.680851 (-1150 700);
DISPLAY INVISIBLE (-1150 700);
FORCEPROP 2 LAST CDS_LIB standard
J 0
(-1375 650);
DISPLAY INVISIBLE (-1375 650);
FORCEPROP 1 LAST OFFPAGE TRUE
J 0
(-1050 525);
DISPLAY 0.872340 (-1050 525);
PAINT GREEN (-1050 525);
DISPLAY INVISIBLE (-1050 525);
FORCEPROP 1 LAST COMMENT_BODY TRUE
J 0
(-1420 555);
DISPLAY 0.872340 (-1420 555);
PAINT GREEN (-1420 555);
DISPLAY INVISIBLE (-1420 555);
FORCEADD Q_RES..1
(-2550 2700);
FORCEPROP 1 LAST LOCATION R649
J 0
(-2450 2700);
DISPLAY 0.489362 (-2450 2700);
PAINT SKYBLUE (-2450 2700);
FORCEPROP 0 LAST $SEC 1
J 0
(-2450 2750);
DISPLAY 0.680851 (-2450 2750);
PAINT MONO (-2450 2750);
DISPLAY INVISIBLE (-2450 2750);
FORCEPROP 0 LAST CDS_SEC 1
J 0
(-2450 2750);
DISPLAY 0.680851 (-2450 2750);
DISPLAY INVISIBLE (-2450 2750);
FORCEPROP 1 LASTPIN (-2650 2700) $PN 1
J 0
(-2638 2712);
DISPLAY 0.489362 (-2638 2712);
PAINT MONO (-2638 2712);
FORCEPROP 1 LASTPIN (-2450 2700) $PN 2
J 0
(-2488 2712);
DISPLAY 0.489362 (-2488 2712);
PAINT MONO (-2488 2712);
FORCEPROP 1 LAST VALUE 33
J 2
(-2675 2700);
DISPLAY 0.489362 (-2675 2700);
PAINT SKYBLUE (-2675 2700);
FORCEPROP 2 LAST ROOM RST_CPU0_PLD_TO_DIMM
J 2
(-2525 2800);
DISPLAY 0.744681 (-2525 2800);
PAINT RED (-2525 2800);
DISPLAY INVISIBLE (-2525 2800);
FORCEPROP 1 LAST PACK_TYPE 0402LF
J 2
(-2375 2625);
DISPLAY 0.489362 (-2375 2625);
PAINT SKYBLUE (-2375 2625);
DISPLAY INVISIBLE (-2375 2625);
FORCEPROP 1 LAST PART_NUMBER CS03302JB29
J 2
(-2450 2750);
DISPLAY 0.489362 (-2450 2750);
PAINT SKYBLUE (-2450 2750);
DISPLAY INVISIBLE (-2450 2750);
FORCEPROP 1 LAST TOLERANCE 5%
J 0
(-2675 2675);
DISPLAY 0.489362 (-2675 2675);
PAINT SKYBLUE (-2675 2675);
DISPLAY INVISIBLE (-2675 2675);
FORCEPROP 1 LAST MATERIAL CHIP
J 2
(-2375 2675);
DISPLAY 0.489362 (-2375 2675);
PAINT SKYBLUE (-2375 2675);
DISPLAY INVISIBLE (-2375 2675);
FORCEPROP 1 LAST WATTAGE 1/16W
J 2
(-2625 2625);
DISPLAY 0.489362 (-2625 2625);
PAINT SKYBLUE (-2625 2625);
DISPLAY INVISIBLE (-2625 2625);
FORCEPROP 1 LAST PATH I2057
J 0
(-2600 2850);
DISPLAY 0.978723 (-2600 2850);
PAINT WHITE (-2600 2850);
DISPLAY INVISIBLE (-2600 2850);
FORCEPROP 2 LAST CDS_LIB pure_quanta
J 0
(-2550 2700);
DISPLAY INVISIBLE (-2550 2700);
FORCEPROP 2 LAST BOM_COST MEM
J 2
(-2525 2850);
DISPLAY 0.744681 (-2525 2850);
PAINT WHITE (-2525 2850);
DISPLAY INVISIBLE (-2525 2850);
FORCEADD Q_RES..1
(-2550 2750);
FORCEPROP 1 LAST LOCATION R671
J 0
(-2450 2750);
DISPLAY 0.489362 (-2450 2750);
PAINT SKYBLUE (-2450 2750);
FORCEPROP 2 LAST $SEC 1
J 0
(-2600 2950);
DISPLAY 0.680851 (-2600 2950);
PAINT MONO (-2600 2950);
DISPLAY INVISIBLE (-2600 2950);
FORCEPROP 2 LAST CDS_SEC 1
J 0
(-2600 2950);
DISPLAY 1.021277 (-2600 2950);
DISPLAY INVISIBLE (-2600 2950);
FORCEPROP 1 LASTPIN (-2650 2750) $PN 1
J 0
(-2638 2762);
DISPLAY 0.489362 (-2638 2762);
PAINT MONO (-2638 2762);
FORCEPROP 1 LASTPIN (-2450 2750) $PN 2
J 0
(-2488 2762);
DISPLAY 0.489362 (-2488 2762);
PAINT MONO (-2488 2762);
FORCEPROP 1 LAST VALUE 0
J 2
(-2675 2750);
DISPLAY 0.489362 (-2675 2750);
PAINT SKYBLUE (-2675 2750);
FORCEPROP 2 LAST CDS_LIB pure_quanta
J 0
(-2550 2750);
DISPLAY INVISIBLE (-2550 2750);
FORCEPROP 1 LAST PATH I2058
J 0
(-2600 2900);
DISPLAY 0.978723 (-2600 2900);
PAINT WHITE (-2600 2900);
DISPLAY INVISIBLE (-2600 2900);
FORCEPROP 2 LAST BOM_COST MEM
J 2
(-2525 2900);
DISPLAY 0.744681 (-2525 2900);
PAINT WHITE (-2525 2900);
DISPLAY INVISIBLE (-2525 2900);
FORCEPROP 1 LAST WATTAGE 1/16W
J 2
(-2625 2675);
DISPLAY 0.489362 (-2625 2675);
PAINT SKYBLUE (-2625 2675);
DISPLAY INVISIBLE (-2625 2675);
FORCEPROP 1 LAST MATERIAL CHIP
J 2
(-2375 2725);
DISPLAY 0.489362 (-2375 2725);
PAINT SKYBLUE (-2375 2725);
DISPLAY INVISIBLE (-2375 2725);
FORCEPROP 1 LAST TOLERANCE 5%
J 0
(-2675 2725);
DISPLAY 0.489362 (-2675 2725);
PAINT SKYBLUE (-2675 2725);
DISPLAY INVISIBLE (-2675 2725);
FORCEPROP 1 LAST PART_NUMBER CS00002JB38
J 2
(-2450 2800);
DISPLAY 0.489362 (-2450 2800);
PAINT SKYBLUE (-2450 2800);
DISPLAY INVISIBLE (-2450 2800);
FORCEPROP 1 LAST PACK_TYPE 0402LF
J 2
(-2375 2675);
DISPLAY 0.489362 (-2375 2675);
PAINT SKYBLUE (-2375 2675);
DISPLAY INVISIBLE (-2375 2675);
FORCEPROP 2 LAST ROOM RST_CPU0_PLD_TO_DIMM
J 2
(-2525 2850);
DISPLAY 0.744681 (-2525 2850);
PAINT RED (-2525 2850);
DISPLAY INVISIBLE (-2525 2850);
FORCEADD Q_RES..1
(-2550 2550);
FORCEPROP 1 LAST LOCATION R685
J 0
(-2450 2550);
DISPLAY 0.489362 (-2450 2550);
PAINT SKYBLUE (-2450 2550);
FORCEPROP 0 LAST $SEC 1
J 0
(-2425 2600);
DISPLAY 0.680851 (-2425 2600);
PAINT MONO (-2425 2600);
DISPLAY INVISIBLE (-2425 2600);
FORCEPROP 0 LAST CDS_SEC 1
J 0
(-2425 2600);
DISPLAY 1.021277 (-2425 2600);
DISPLAY INVISIBLE (-2425 2600);
FORCEPROP 1 LASTPIN (-2650 2550) $PN 1
J 0
(-2638 2562);
DISPLAY 0.489362 (-2638 2562);
PAINT MONO (-2638 2562);
FORCEPROP 1 LASTPIN (-2450 2550) $PN 2
J 0
(-2488 2562);
DISPLAY 0.489362 (-2488 2562);
PAINT MONO (-2488 2562);
FORCEPROP 1 LAST VALUE 33
J 2
(-2675 2550);
DISPLAY 0.489362 (-2675 2550);
PAINT SKYBLUE (-2675 2550);
FORCEPROP 2 LAST ROOM RST_CPU0_PLD_TO_DIMM
J 2
(-2525 2650);
DISPLAY 0.744681 (-2525 2650);
PAINT RED (-2525 2650);
DISPLAY INVISIBLE (-2525 2650);
FORCEPROP 1 LAST PACK_TYPE 0402LF
J 2
(-2375 2475);
DISPLAY 0.489362 (-2375 2475);
PAINT SKYBLUE (-2375 2475);
DISPLAY INVISIBLE (-2375 2475);
FORCEPROP 1 LAST PART_NUMBER CS03302JB29
J 2
(-2450 2600);
DISPLAY 0.489362 (-2450 2600);
PAINT SKYBLUE (-2450 2600);
DISPLAY INVISIBLE (-2450 2600);
FORCEPROP 1 LAST TOLERANCE 5%
J 0
(-2675 2525);
DISPLAY 0.489362 (-2675 2525);
PAINT SKYBLUE (-2675 2525);
DISPLAY INVISIBLE (-2675 2525);
FORCEPROP 1 LAST MATERIAL CHIP
J 2
(-2375 2525);
DISPLAY 0.489362 (-2375 2525);
PAINT SKYBLUE (-2375 2525);
DISPLAY INVISIBLE (-2375 2525);
FORCEPROP 1 LAST WATTAGE 1/16W
J 2
(-2625 2475);
DISPLAY 0.489362 (-2625 2475);
PAINT SKYBLUE (-2625 2475);
DISPLAY INVISIBLE (-2625 2475);
FORCEPROP 1 LAST PATH I2059
J 0
(-2600 2700);
DISPLAY 0.978723 (-2600 2700);
PAINT WHITE (-2600 2700);
DISPLAY INVISIBLE (-2600 2700);
FORCEPROP 2 LAST CDS_LIB pure_quanta
J 0
(-2550 2550);
DISPLAY INVISIBLE (-2550 2550);
FORCEPROP 2 LAST BOM_COST MEM
J 2
(-2525 2700);
DISPLAY 0.744681 (-2525 2700);
PAINT WHITE (-2525 2700);
DISPLAY INVISIBLE (-2525 2700);
FORCEADD Q_RES..1
(-2550 2600);
FORCEPROP 1 LAST LOCATION R957
J 0
(-2450 2600);
DISPLAY 0.489362 (-2450 2600);
PAINT SKYBLUE (-2450 2600);
FORCEPROP 0 LAST $SEC 1
J 0
(-2450 2650);
DISPLAY 0.680851 (-2450 2650);
PAINT MONO (-2450 2650);
DISPLAY INVISIBLE (-2450 2650);
FORCEPROP 0 LAST CDS_SEC 1
J 0
(-2450 2650);
DISPLAY 0.680851 (-2450 2650);
DISPLAY INVISIBLE (-2450 2650);
FORCEPROP 1 LASTPIN (-2650 2600) $PN 1
J 0
(-2638 2612);
DISPLAY 0.489362 (-2638 2612);
PAINT MONO (-2638 2612);
FORCEPROP 1 LASTPIN (-2450 2600) $PN 2
J 0
(-2488 2612);
DISPLAY 0.489362 (-2488 2612);
PAINT MONO (-2488 2612);
FORCEPROP 1 LAST VALUE 33
J 2
(-2675 2600);
DISPLAY 0.489362 (-2675 2600);
PAINT SKYBLUE (-2675 2600);
FORCEPROP 2 LAST ROOM RST_CPU0_PLD_TO_DIMM
J 2
(-2525 2700);
DISPLAY 0.744681 (-2525 2700);
PAINT RED (-2525 2700);
DISPLAY INVISIBLE (-2525 2700);
FORCEPROP 1 LAST PACK_TYPE 0402LF
J 2
(-2375 2525);
DISPLAY 0.489362 (-2375 2525);
PAINT SKYBLUE (-2375 2525);
DISPLAY INVISIBLE (-2375 2525);
FORCEPROP 1 LAST PART_NUMBER CS03302JB29
J 2
(-2450 2650);
DISPLAY 0.489362 (-2450 2650);
PAINT SKYBLUE (-2450 2650);
DISPLAY INVISIBLE (-2450 2650);
FORCEPROP 1 LAST TOLERANCE 5%
J 0
(-2675 2575);
DISPLAY 0.489362 (-2675 2575);
PAINT SKYBLUE (-2675 2575);
DISPLAY INVISIBLE (-2675 2575);
FORCEPROP 1 LAST MATERIAL CHIP
J 2
(-2375 2575);
DISPLAY 0.489362 (-2375 2575);
PAINT SKYBLUE (-2375 2575);
DISPLAY INVISIBLE (-2375 2575);
FORCEPROP 1 LAST WATTAGE 1/16W
J 2
(-2625 2525);
DISPLAY 0.489362 (-2625 2525);
PAINT SKYBLUE (-2625 2525);
DISPLAY INVISIBLE (-2625 2525);
FORCEPROP 1 LAST PATH I2060
J 0
(-2600 2750);
DISPLAY 0.978723 (-2600 2750);
PAINT WHITE (-2600 2750);
DISPLAY INVISIBLE (-2600 2750);
FORCEPROP 2 LAST BOM_COST MEM
J 2
(-2525 2750);
DISPLAY 0.744681 (-2525 2750);
PAINT WHITE (-2525 2750);
DISPLAY INVISIBLE (-2525 2750);
FORCEPROP 2 LAST CDS_LIB pure_quanta
J 0
(-2550 2600);
DISPLAY INVISIBLE (-2550 2600);
FORCEADD Q_RES..1
(-2550 2500);
FORCEPROP 1 LAST LOCATION R487
J 0
(-2450 2500);
DISPLAY 0.489362 (-2450 2500);
PAINT SKYBLUE (-2450 2500);
FORCEPROP 0 LAST $SEC 1
J 0
(-2450 2550);
DISPLAY 0.680851 (-2450 2550);
PAINT MONO (-2450 2550);
DISPLAY INVISIBLE (-2450 2550);
FORCEPROP 0 LAST CDS_SEC 1
J 0
(-2450 2550);
DISPLAY 0.680851 (-2450 2550);
DISPLAY INVISIBLE (-2450 2550);
FORCEPROP 1 LASTPIN (-2650 2500) $PN 1
J 0
(-2638 2512);
DISPLAY 0.489362 (-2638 2512);
PAINT MONO (-2638 2512);
FORCEPROP 1 LASTPIN (-2450 2500) $PN 2
J 0
(-2488 2512);
DISPLAY 0.489362 (-2488 2512);
PAINT MONO (-2488 2512);
FORCEPROP 1 LAST VALUE 33
J 2
(-2675 2500);
DISPLAY 0.489362 (-2675 2500);
PAINT SKYBLUE (-2675 2500);
FORCEPROP 2 LAST ROOM RST_CPU0_PLD_TO_DIMM
J 2
(-2525 2600);
DISPLAY 0.744681 (-2525 2600);
PAINT RED (-2525 2600);
DISPLAY INVISIBLE (-2525 2600);
FORCEPROP 1 LAST PACK_TYPE 0402LF
J 2
(-2375 2425);
DISPLAY 0.489362 (-2375 2425);
PAINT SKYBLUE (-2375 2425);
DISPLAY INVISIBLE (-2375 2425);
FORCEPROP 1 LAST PART_NUMBER CS03302JB29
J 2
(-2450 2550);
DISPLAY 0.489362 (-2450 2550);
PAINT SKYBLUE (-2450 2550);
DISPLAY INVISIBLE (-2450 2550);
FORCEPROP 1 LAST TOLERANCE 5%
J 0
(-2675 2475);
DISPLAY 0.489362 (-2675 2475);
PAINT SKYBLUE (-2675 2475);
DISPLAY INVISIBLE (-2675 2475);
FORCEPROP 1 LAST MATERIAL CHIP
J 2
(-2375 2475);
DISPLAY 0.489362 (-2375 2475);
PAINT SKYBLUE (-2375 2475);
DISPLAY INVISIBLE (-2375 2475);
FORCEPROP 1 LAST WATTAGE 1/16W
J 2
(-2625 2425);
DISPLAY 0.489362 (-2625 2425);
PAINT SKYBLUE (-2625 2425);
DISPLAY INVISIBLE (-2625 2425);
FORCEPROP 1 LAST PATH I2061
J 0
(-2600 2650);
DISPLAY 0.978723 (-2600 2650);
PAINT WHITE (-2600 2650);
DISPLAY INVISIBLE (-2600 2650);
FORCEPROP 2 LAST CDS_LIB pure_quanta
J 0
(-2550 2500);
DISPLAY INVISIBLE (-2550 2500);
FORCEPROP 2 LAST BOM_COST MEM
J 2
(-2525 2650);
DISPLAY 0.744681 (-2525 2650);
PAINT WHITE (-2525 2650);
DISPLAY INVISIBLE (-2525 2650);
FORCEADD Q_RES..1
(-2550 2450);
FORCEPROP 1 LAST LOCATION R644
J 0
(-2450 2450);
DISPLAY 0.489362 (-2450 2450);
PAINT SKYBLUE (-2450 2450);
FORCEPROP 0 LAST $SEC 1
J 0
(-2450 2500);
DISPLAY 0.680851 (-2450 2500);
PAINT MONO (-2450 2500);
DISPLAY INVISIBLE (-2450 2500);
FORCEPROP 0 LAST CDS_SEC 1
J 0
(-2450 2500);
DISPLAY 0.680851 (-2450 2500);
DISPLAY INVISIBLE (-2450 2500);
FORCEPROP 1 LASTPIN (-2650 2450) $PN 1
J 0
(-2638 2462);
DISPLAY 0.489362 (-2638 2462);
PAINT MONO (-2638 2462);
FORCEPROP 1 LASTPIN (-2450 2450) $PN 2
J 0
(-2488 2462);
DISPLAY 0.489362 (-2488 2462);
PAINT MONO (-2488 2462);
FORCEPROP 1 LAST VALUE 33
J 2
(-2675 2450);
DISPLAY 0.489362 (-2675 2450);
PAINT SKYBLUE (-2675 2450);
FORCEPROP 2 LAST ROOM RST_CPU0_PLD_TO_DIMM
J 2
(-2525 2550);
DISPLAY 0.744681 (-2525 2550);
PAINT RED (-2525 2550);
DISPLAY INVISIBLE (-2525 2550);
FORCEPROP 1 LAST PACK_TYPE 0402LF
J 2
(-2375 2375);
DISPLAY 0.489362 (-2375 2375);
PAINT SKYBLUE (-2375 2375);
DISPLAY INVISIBLE (-2375 2375);
FORCEPROP 1 LAST PART_NUMBER CS03302JB29
J 2
(-2450 2500);
DISPLAY 0.489362 (-2450 2500);
PAINT SKYBLUE (-2450 2500);
DISPLAY INVISIBLE (-2450 2500);
FORCEPROP 1 LAST TOLERANCE 5%
J 0
(-2675 2425);
DISPLAY 0.489362 (-2675 2425);
PAINT SKYBLUE (-2675 2425);
DISPLAY INVISIBLE (-2675 2425);
FORCEPROP 1 LAST MATERIAL CHIP
J 2
(-2375 2425);
DISPLAY 0.489362 (-2375 2425);
PAINT SKYBLUE (-2375 2425);
DISPLAY INVISIBLE (-2375 2425);
FORCEPROP 1 LAST WATTAGE 1/16W
J 2
(-2625 2375);
DISPLAY 0.489362 (-2625 2375);
PAINT SKYBLUE (-2625 2375);
DISPLAY INVISIBLE (-2625 2375);
FORCEPROP 1 LAST PATH I2062
J 0
(-2600 2600);
DISPLAY 0.978723 (-2600 2600);
PAINT WHITE (-2600 2600);
DISPLAY INVISIBLE (-2600 2600);
FORCEPROP 2 LAST CDS_LIB pure_quanta
J 0
(-2550 2450);
DISPLAY INVISIBLE (-2550 2450);
FORCEPROP 2 LAST BOM_COST MEM
J 2
(-2525 2600);
DISPLAY 0.744681 (-2525 2600);
PAINT WHITE (-2525 2600);
DISPLAY INVISIBLE (-2525 2600);
FORCEADD Q_RES..1
(-2550 2350);
FORCEPROP 1 LAST LOCATION R175
J 0
(-2450 2350);
DISPLAY 0.489362 (-2450 2350);
PAINT SKYBLUE (-2450 2350);
FORCEPROP 0 LAST $SEC 1
J 0
(-2425 2400);
DISPLAY 0.680851 (-2425 2400);
PAINT MONO (-2425 2400);
DISPLAY INVISIBLE (-2425 2400);
FORCEPROP 0 LAST CDS_SEC 1
J 0
(-2425 2400);
DISPLAY 1.021277 (-2425 2400);
DISPLAY INVISIBLE (-2425 2400);
FORCEPROP 1 LASTPIN (-2650 2350) $PN 1
J 0
(-2638 2362);
DISPLAY 0.489362 (-2638 2362);
PAINT MONO (-2638 2362);
FORCEPROP 1 LASTPIN (-2450 2350) $PN 2
J 0
(-2488 2362);
DISPLAY 0.489362 (-2488 2362);
PAINT MONO (-2488 2362);
FORCEPROP 1 LAST VALUE 33
J 2
(-2675 2350);
DISPLAY 0.489362 (-2675 2350);
PAINT SKYBLUE (-2675 2350);
FORCEPROP 2 LAST ROOM RST_CPU0_PLD_TO_DIMM
J 2
(-2525 2450);
DISPLAY 0.744681 (-2525 2450);
PAINT RED (-2525 2450);
DISPLAY INVISIBLE (-2525 2450);
FORCEPROP 1 LAST PACK_TYPE 0402LF
J 2
(-2375 2275);
DISPLAY 0.489362 (-2375 2275);
PAINT SKYBLUE (-2375 2275);
DISPLAY INVISIBLE (-2375 2275);
FORCEPROP 1 LAST PART_NUMBER CS03302JB29
J 2
(-2450 2400);
DISPLAY 0.489362 (-2450 2400);
PAINT SKYBLUE (-2450 2400);
DISPLAY INVISIBLE (-2450 2400);
FORCEPROP 1 LAST TOLERANCE 5%
J 0
(-2675 2325);
DISPLAY 0.489362 (-2675 2325);
PAINT SKYBLUE (-2675 2325);
DISPLAY INVISIBLE (-2675 2325);
FORCEPROP 1 LAST MATERIAL CHIP
J 2
(-2375 2325);
DISPLAY 0.489362 (-2375 2325);
PAINT SKYBLUE (-2375 2325);
DISPLAY INVISIBLE (-2375 2325);
FORCEPROP 1 LAST WATTAGE 1/16W
J 2
(-2625 2275);
DISPLAY 0.489362 (-2625 2275);
PAINT SKYBLUE (-2625 2275);
DISPLAY INVISIBLE (-2625 2275);
FORCEPROP 1 LAST PATH I2063
J 0
(-2600 2500);
DISPLAY 0.978723 (-2600 2500);
PAINT WHITE (-2600 2500);
DISPLAY INVISIBLE (-2600 2500);
FORCEPROP 2 LAST CDS_LIB pure_quanta
J 0
(-2550 2350);
DISPLAY INVISIBLE (-2550 2350);
FORCEPROP 2 LAST BOM_COST MEM
J 2
(-2525 2500);
DISPLAY 0.744681 (-2525 2500);
PAINT WHITE (-2525 2500);
DISPLAY INVISIBLE (-2525 2500);
FORCEADD Q_RES..1
(-2550 2300);
FORCEPROP 1 LAST LOCATION R793
J 0
(-2450 2300);
DISPLAY 0.489362 (-2450 2300);
PAINT SKYBLUE (-2450 2300);
FORCEPROP 0 LAST $SEC 1
J 0
(-2425 2350);
DISPLAY 0.680851 (-2425 2350);
PAINT MONO (-2425 2350);
DISPLAY INVISIBLE (-2425 2350);
FORCEPROP 0 LAST CDS_SEC 1
J 0
(-2425 2350);
DISPLAY 1.021277 (-2425 2350);
DISPLAY INVISIBLE (-2425 2350);
FORCEPROP 1 LASTPIN (-2650 2300) $PN 1
J 0
(-2638 2312);
DISPLAY 0.489362 (-2638 2312);
PAINT MONO (-2638 2312);
FORCEPROP 1 LASTPIN (-2450 2300) $PN 2
J 0
(-2488 2312);
DISPLAY 0.489362 (-2488 2312);
PAINT MONO (-2488 2312);
FORCEPROP 1 LAST VALUE 33
J 2
(-2675 2300);
DISPLAY 0.489362 (-2675 2300);
PAINT SKYBLUE (-2675 2300);
FORCEPROP 2 LAST ROOM RST_CPU0_PLD_TO_DIMM
J 2
(-2525 2400);
DISPLAY 0.744681 (-2525 2400);
PAINT RED (-2525 2400);
DISPLAY INVISIBLE (-2525 2400);
FORCEPROP 1 LAST PACK_TYPE 0402LF
J 2
(-2375 2225);
DISPLAY 0.489362 (-2375 2225);
PAINT SKYBLUE (-2375 2225);
DISPLAY INVISIBLE (-2375 2225);
FORCEPROP 1 LAST PART_NUMBER CS03302JB29
J 2
(-2450 2350);
DISPLAY 0.489362 (-2450 2350);
PAINT SKYBLUE (-2450 2350);
DISPLAY INVISIBLE (-2450 2350);
FORCEPROP 1 LAST TOLERANCE 5%
J 0
(-2675 2275);
DISPLAY 0.489362 (-2675 2275);
PAINT SKYBLUE (-2675 2275);
DISPLAY INVISIBLE (-2675 2275);
FORCEPROP 1 LAST MATERIAL CHIP
J 2
(-2375 2275);
DISPLAY 0.489362 (-2375 2275);
PAINT SKYBLUE (-2375 2275);
DISPLAY INVISIBLE (-2375 2275);
FORCEPROP 1 LAST WATTAGE 1/16W
J 2
(-2625 2225);
DISPLAY 0.489362 (-2625 2225);
PAINT SKYBLUE (-2625 2225);
DISPLAY INVISIBLE (-2625 2225);
FORCEPROP 1 LAST PATH I2064
J 0
(-2600 2450);
DISPLAY 0.978723 (-2600 2450);
PAINT WHITE (-2600 2450);
DISPLAY INVISIBLE (-2600 2450);
FORCEPROP 2 LAST BOM_COST MEM
J 2
(-2525 2450);
DISPLAY 0.744681 (-2525 2450);
PAINT WHITE (-2525 2450);
DISPLAY INVISIBLE (-2525 2450);
FORCEPROP 2 LAST CDS_LIB pure_quanta
J 0
(-2550 2300);
DISPLAY INVISIBLE (-2550 2300);
FORCEADD Q_RES..1
(-2550 2250);
FORCEPROP 1 LAST LOCATION R686
J 0
(-2450 2250);
DISPLAY 0.489362 (-2450 2250);
PAINT SKYBLUE (-2450 2250);
FORCEPROP 0 LAST $SEC 1
J 0
(-2425 2300);
DISPLAY 0.680851 (-2425 2300);
PAINT MONO (-2425 2300);
DISPLAY INVISIBLE (-2425 2300);
FORCEPROP 0 LAST CDS_SEC 1
J 0
(-2425 2300);
DISPLAY 1.021277 (-2425 2300);
DISPLAY INVISIBLE (-2425 2300);
FORCEPROP 1 LASTPIN (-2650 2250) $PN 1
J 0
(-2638 2262);
DISPLAY 0.489362 (-2638 2262);
PAINT MONO (-2638 2262);
FORCEPROP 1 LASTPIN (-2450 2250) $PN 2
J 0
(-2488 2262);
DISPLAY 0.489362 (-2488 2262);
PAINT MONO (-2488 2262);
FORCEPROP 1 LAST VALUE 33
J 2
(-2675 2250);
DISPLAY 0.489362 (-2675 2250);
PAINT SKYBLUE (-2675 2250);
FORCEPROP 2 LAST ROOM RST_CPU0_PLD_TO_DIMM
J 2
(-2525 2350);
DISPLAY 0.744681 (-2525 2350);
PAINT RED (-2525 2350);
DISPLAY INVISIBLE (-2525 2350);
FORCEPROP 1 LAST PACK_TYPE 0402LF
J 2
(-2375 2175);
DISPLAY 0.489362 (-2375 2175);
PAINT SKYBLUE (-2375 2175);
DISPLAY INVISIBLE (-2375 2175);
FORCEPROP 1 LAST PART_NUMBER CS03302JB29
J 2
(-2450 2300);
DISPLAY 0.489362 (-2450 2300);
PAINT SKYBLUE (-2450 2300);
DISPLAY INVISIBLE (-2450 2300);
FORCEPROP 1 LAST TOLERANCE 5%
J 0
(-2675 2225);
DISPLAY 0.489362 (-2675 2225);
PAINT SKYBLUE (-2675 2225);
DISPLAY INVISIBLE (-2675 2225);
FORCEPROP 1 LAST MATERIAL CHIP
J 2
(-2375 2225);
DISPLAY 0.489362 (-2375 2225);
PAINT SKYBLUE (-2375 2225);
DISPLAY INVISIBLE (-2375 2225);
FORCEPROP 1 LAST WATTAGE 1/16W
J 2
(-2625 2175);
DISPLAY 0.489362 (-2625 2175);
PAINT SKYBLUE (-2625 2175);
DISPLAY INVISIBLE (-2625 2175);
FORCEPROP 1 LAST PATH I2065
J 0
(-2600 2400);
DISPLAY 0.978723 (-2600 2400);
PAINT WHITE (-2600 2400);
DISPLAY INVISIBLE (-2600 2400);
FORCEPROP 2 LAST BOM_COST MEM
J 2
(-2525 2400);
DISPLAY 0.744681 (-2525 2400);
PAINT WHITE (-2525 2400);
DISPLAY INVISIBLE (-2525 2400);
FORCEPROP 2 LAST CDS_LIB pure_quanta
J 0
(-2550 2250);
DISPLAY INVISIBLE (-2550 2250);
FORCEADD Q_RES..1
(-2550 2200);
FORCEPROP 1 LAST LOCATION R490
J 0
(-2450 2200);
DISPLAY 0.489362 (-2450 2200);
PAINT SKYBLUE (-2450 2200);
FORCEPROP 2 LAST $SEC 1
J 0
(-2600 2400);
DISPLAY 0.680851 (-2600 2400);
PAINT MONO (-2600 2400);
DISPLAY INVISIBLE (-2600 2400);
FORCEPROP 2 LAST CDS_SEC 1
J 0
(-2600 2400);
DISPLAY 0.680851 (-2600 2400);
DISPLAY INVISIBLE (-2600 2400);
FORCEPROP 1 LASTPIN (-2650 2200) $PN 1
J 0
(-2638 2212);
DISPLAY 0.489362 (-2638 2212);
PAINT MONO (-2638 2212);
FORCEPROP 1 LASTPIN (-2450 2200) $PN 2
J 0
(-2488 2212);
DISPLAY 0.489362 (-2488 2212);
PAINT MONO (-2488 2212);
FORCEPROP 1 LAST VALUE 33
J 2
(-2675 2200);
DISPLAY 0.489362 (-2675 2200);
PAINT SKYBLUE (-2675 2200);
FORCEPROP 2 LAST ROOM RST_CPU0_PLD_TO_DIMM
J 2
(-2525 2300);
DISPLAY 0.744681 (-2525 2300);
PAINT RED (-2525 2300);
DISPLAY INVISIBLE (-2525 2300);
FORCEPROP 1 LAST PACK_TYPE 0402LF
J 2
(-2375 2125);
DISPLAY 0.489362 (-2375 2125);
PAINT SKYBLUE (-2375 2125);
DISPLAY INVISIBLE (-2375 2125);
FORCEPROP 1 LAST PART_NUMBER CS03302JB29
J 2
(-2450 2250);
DISPLAY 0.489362 (-2450 2250);
PAINT SKYBLUE (-2450 2250);
DISPLAY INVISIBLE (-2450 2250);
FORCEPROP 1 LAST TOLERANCE 5%
J 0
(-2675 2175);
DISPLAY 0.489362 (-2675 2175);
PAINT SKYBLUE (-2675 2175);
DISPLAY INVISIBLE (-2675 2175);
FORCEPROP 1 LAST MATERIAL CHIP
J 2
(-2375 2175);
DISPLAY 0.489362 (-2375 2175);
PAINT SKYBLUE (-2375 2175);
DISPLAY INVISIBLE (-2375 2175);
FORCEPROP 1 LAST WATTAGE 1/16W
J 2
(-2625 2125);
DISPLAY 0.489362 (-2625 2125);
PAINT SKYBLUE (-2625 2125);
DISPLAY INVISIBLE (-2625 2125);
FORCEPROP 1 LAST PATH I2066
J 0
(-2600 2350);
DISPLAY 0.978723 (-2600 2350);
PAINT WHITE (-2600 2350);
DISPLAY INVISIBLE (-2600 2350);
FORCEPROP 2 LAST CDS_LIB pure_quanta
J 0
(-2550 2200);
DISPLAY INVISIBLE (-2550 2200);
FORCEPROP 2 LAST BOM_COST MEM
J 2
(-2525 2350);
DISPLAY 0.744681 (-2525 2350);
PAINT WHITE (-2525 2350);
DISPLAY INVISIBLE (-2525 2350);
FORCEADD Q_RES..1
(-2550 2150);
FORCEPROP 1 LAST LOCATION R494
J 0
(-2450 2150);
DISPLAY 0.489362 (-2450 2150);
PAINT SKYBLUE (-2450 2150);
FORCEPROP 2 LAST $SEC 1
J 0
(-2600 2350);
DISPLAY 0.680851 (-2600 2350);
PAINT MONO (-2600 2350);
DISPLAY INVISIBLE (-2600 2350);
FORCEPROP 2 LAST CDS_SEC 1
J 0
(-2600 2350);
DISPLAY 0.680851 (-2600 2350);
DISPLAY INVISIBLE (-2600 2350);
FORCEPROP 1 LASTPIN (-2650 2150) $PN 1
J 0
(-2638 2162);
DISPLAY 0.489362 (-2638 2162);
PAINT MONO (-2638 2162);
FORCEPROP 1 LASTPIN (-2450 2150) $PN 2
J 0
(-2488 2162);
DISPLAY 0.489362 (-2488 2162);
PAINT MONO (-2488 2162);
FORCEPROP 1 LAST VALUE 33
J 2
(-2675 2150);
DISPLAY 0.489362 (-2675 2150);
PAINT SKYBLUE (-2675 2150);
FORCEPROP 2 LAST ROOM RST_CPU0_PLD_TO_DIMM
J 2
(-2525 2250);
DISPLAY 0.744681 (-2525 2250);
PAINT RED (-2525 2250);
DISPLAY INVISIBLE (-2525 2250);
FORCEPROP 1 LAST PACK_TYPE 0402LF
J 2
(-2375 2075);
DISPLAY 0.489362 (-2375 2075);
PAINT SKYBLUE (-2375 2075);
DISPLAY INVISIBLE (-2375 2075);
FORCEPROP 1 LAST PART_NUMBER CS03302JB29
J 2
(-2450 2200);
DISPLAY 0.489362 (-2450 2200);
PAINT SKYBLUE (-2450 2200);
DISPLAY INVISIBLE (-2450 2200);
FORCEPROP 1 LAST TOLERANCE 5%
J 0
(-2675 2125);
DISPLAY 0.489362 (-2675 2125);
PAINT SKYBLUE (-2675 2125);
DISPLAY INVISIBLE (-2675 2125);
FORCEPROP 1 LAST MATERIAL CHIP
J 2
(-2375 2125);
DISPLAY 0.489362 (-2375 2125);
PAINT SKYBLUE (-2375 2125);
DISPLAY INVISIBLE (-2375 2125);
FORCEPROP 1 LAST WATTAGE 1/16W
J 2
(-2625 2075);
DISPLAY 0.489362 (-2625 2075);
PAINT SKYBLUE (-2625 2075);
DISPLAY INVISIBLE (-2625 2075);
FORCEPROP 1 LAST PATH I2067
J 0
(-2600 2300);
DISPLAY 0.978723 (-2600 2300);
PAINT WHITE (-2600 2300);
DISPLAY INVISIBLE (-2600 2300);
FORCEPROP 2 LAST CDS_LIB pure_quanta
J 0
(-2550 2150);
DISPLAY INVISIBLE (-2550 2150);
FORCEPROP 2 LAST BOM_COST MEM
J 2
(-2525 2300);
DISPLAY 0.744681 (-2525 2300);
PAINT WHITE (-2525 2300);
DISPLAY INVISIBLE (-2525 2300);
FORCEADD Q_RES..1
(-2550 2100);
FORCEPROP 1 LAST LOCATION R865
J 0
(-2450 2100);
DISPLAY 0.489362 (-2450 2100);
PAINT SKYBLUE (-2450 2100);
FORCEPROP 0 LAST $SEC 1
J 0
(-2450 2150);
DISPLAY 0.680851 (-2450 2150);
PAINT MONO (-2450 2150);
DISPLAY INVISIBLE (-2450 2150);
FORCEPROP 0 LAST CDS_SEC 1
J 0
(-2450 2150);
DISPLAY 0.680851 (-2450 2150);
DISPLAY INVISIBLE (-2450 2150);
FORCEPROP 1 LASTPIN (-2650 2100) $PN 1
J 0
(-2638 2112);
DISPLAY 0.489362 (-2638 2112);
PAINT MONO (-2638 2112);
FORCEPROP 1 LASTPIN (-2450 2100) $PN 2
J 0
(-2488 2112);
DISPLAY 0.489362 (-2488 2112);
PAINT MONO (-2488 2112);
FORCEPROP 1 LAST VALUE 33
J 2
(-2675 2100);
DISPLAY 0.489362 (-2675 2100);
PAINT SKYBLUE (-2675 2100);
FORCEPROP 2 LAST ROOM RST_CPU0_PLD_TO_DIMM
J 2
(-2525 2200);
DISPLAY 0.744681 (-2525 2200);
PAINT RED (-2525 2200);
DISPLAY INVISIBLE (-2525 2200);
FORCEPROP 1 LAST PACK_TYPE 0402LF
J 2
(-2375 2025);
DISPLAY 0.489362 (-2375 2025);
PAINT SKYBLUE (-2375 2025);
DISPLAY INVISIBLE (-2375 2025);
FORCEPROP 1 LAST PART_NUMBER CS03302JB29
J 2
(-2450 2150);
DISPLAY 0.489362 (-2450 2150);
PAINT SKYBLUE (-2450 2150);
DISPLAY INVISIBLE (-2450 2150);
FORCEPROP 1 LAST TOLERANCE 5%
J 0
(-2675 2075);
DISPLAY 0.489362 (-2675 2075);
PAINT SKYBLUE (-2675 2075);
DISPLAY INVISIBLE (-2675 2075);
FORCEPROP 1 LAST MATERIAL CHIP
J 2
(-2375 2075);
DISPLAY 0.489362 (-2375 2075);
PAINT SKYBLUE (-2375 2075);
DISPLAY INVISIBLE (-2375 2075);
FORCEPROP 1 LAST WATTAGE 1/16W
J 2
(-2625 2025);
DISPLAY 0.489362 (-2625 2025);
PAINT SKYBLUE (-2625 2025);
DISPLAY INVISIBLE (-2625 2025);
FORCEPROP 1 LAST PATH I2068
J 0
(-2600 2250);
DISPLAY 0.978723 (-2600 2250);
PAINT WHITE (-2600 2250);
DISPLAY INVISIBLE (-2600 2250);
FORCEPROP 2 LAST CDS_LIB pure_quanta
J 0
(-2550 2100);
DISPLAY INVISIBLE (-2550 2100);
FORCEPROP 2 LAST BOM_COST MEM
J 2
(-2525 2250);
DISPLAY 0.744681 (-2525 2250);
PAINT WHITE (-2525 2250);
DISPLAY INVISIBLE (-2525 2250);
FORCEADD Q_RES..1
(-2550 2050);
FORCEPROP 1 LAST LOCATION R917
J 0
(-2450 2050);
DISPLAY 0.489362 (-2450 2050);
PAINT SKYBLUE (-2450 2050);
FORCEPROP 0 LAST $SEC 1
J 0
(-2450 2100);
DISPLAY 0.680851 (-2450 2100);
PAINT MONO (-2450 2100);
DISPLAY INVISIBLE (-2450 2100);
FORCEPROP 0 LAST CDS_SEC 1
J 0
(-2450 2100);
DISPLAY 0.680851 (-2450 2100);
DISPLAY INVISIBLE (-2450 2100);
FORCEPROP 1 LASTPIN (-2650 2050) $PN 1
J 0
(-2638 2062);
DISPLAY 0.489362 (-2638 2062);
PAINT MONO (-2638 2062);
FORCEPROP 1 LASTPIN (-2450 2050) $PN 2
J 0
(-2488 2062);
DISPLAY 0.489362 (-2488 2062);
PAINT MONO (-2488 2062);
FORCEPROP 1 LAST VALUE 33
J 2
(-2675 2050);
DISPLAY 0.489362 (-2675 2050);
PAINT SKYBLUE (-2675 2050);
FORCEPROP 2 LAST ROOM RST_CPU0_PLD_TO_DIMM
J 2
(-2525 2150);
DISPLAY 0.744681 (-2525 2150);
PAINT RED (-2525 2150);
DISPLAY INVISIBLE (-2525 2150);
FORCEPROP 1 LAST PACK_TYPE 0402LF
J 2
(-2375 1975);
DISPLAY 0.489362 (-2375 1975);
PAINT SKYBLUE (-2375 1975);
DISPLAY INVISIBLE (-2375 1975);
FORCEPROP 1 LAST PART_NUMBER CS03302JB29
J 2
(-2450 2100);
DISPLAY 0.489362 (-2450 2100);
PAINT SKYBLUE (-2450 2100);
DISPLAY INVISIBLE (-2450 2100);
FORCEPROP 1 LAST TOLERANCE 5%
J 0
(-2675 2025);
DISPLAY 0.489362 (-2675 2025);
PAINT SKYBLUE (-2675 2025);
DISPLAY INVISIBLE (-2675 2025);
FORCEPROP 1 LAST MATERIAL CHIP
J 2
(-2375 2025);
DISPLAY 0.489362 (-2375 2025);
PAINT SKYBLUE (-2375 2025);
DISPLAY INVISIBLE (-2375 2025);
FORCEPROP 1 LAST WATTAGE 1/16W
J 2
(-2625 1975);
DISPLAY 0.489362 (-2625 1975);
PAINT SKYBLUE (-2625 1975);
DISPLAY INVISIBLE (-2625 1975);
FORCEPROP 1 LAST PATH I2069
J 0
(-2600 2200);
DISPLAY 0.978723 (-2600 2200);
PAINT WHITE (-2600 2200);
DISPLAY INVISIBLE (-2600 2200);
FORCEPROP 2 LAST BOM_COST MEM
J 2
(-2525 2200);
DISPLAY 0.744681 (-2525 2200);
PAINT WHITE (-2525 2200);
DISPLAY INVISIBLE (-2525 2200);
FORCEPROP 2 LAST CDS_LIB pure_quanta
J 0
(-2550 2050);
DISPLAY INVISIBLE (-2550 2050);
FORCEADD Q_RES..1
(-2550 1900);
FORCEPROP 1 LAST LOCATION R1064
J 0
(-2450 1900);
DISPLAY 0.489362 (-2450 1900);
PAINT SKYBLUE (-2450 1900);
FORCEPROP 0 LAST $SEC 1
J 0
(-2450 1950);
DISPLAY 0.680851 (-2450 1950);
PAINT MONO (-2450 1950);
DISPLAY INVISIBLE (-2450 1950);
FORCEPROP 0 LAST CDS_SEC 1
J 0
(-2450 1950);
DISPLAY 0.680851 (-2450 1950);
DISPLAY INVISIBLE (-2450 1950);
FORCEPROP 1 LASTPIN (-2650 1900) $PN 1
J 0
(-2638 1912);
DISPLAY 0.489362 (-2638 1912);
PAINT MONO (-2638 1912);
FORCEPROP 1 LASTPIN (-2450 1900) $PN 2
J 0
(-2488 1912);
DISPLAY 0.489362 (-2488 1912);
PAINT MONO (-2488 1912);
FORCEPROP 1 LAST VALUE 33
J 2
(-2675 1900);
DISPLAY 0.489362 (-2675 1900);
PAINT SKYBLUE (-2675 1900);
FORCEPROP 2 LAST ROOM RST_CPU0_PLD_TO_DIMM
J 2
(-2525 2000);
DISPLAY 0.744681 (-2525 2000);
PAINT RED (-2525 2000);
DISPLAY INVISIBLE (-2525 2000);
FORCEPROP 1 LAST PACK_TYPE 0402LF
J 2
(-2375 1825);
DISPLAY 0.489362 (-2375 1825);
PAINT SKYBLUE (-2375 1825);
DISPLAY INVISIBLE (-2375 1825);
FORCEPROP 1 LAST PART_NUMBER CS03302JB29
J 2
(-2450 1950);
DISPLAY 0.489362 (-2450 1950);
PAINT SKYBLUE (-2450 1950);
DISPLAY INVISIBLE (-2450 1950);
FORCEPROP 1 LAST TOLERANCE 5%
J 0
(-2675 1875);
DISPLAY 0.489362 (-2675 1875);
PAINT SKYBLUE (-2675 1875);
DISPLAY INVISIBLE (-2675 1875);
FORCEPROP 1 LAST MATERIAL CHIP
J 2
(-2375 1875);
DISPLAY 0.489362 (-2375 1875);
PAINT SKYBLUE (-2375 1875);
DISPLAY INVISIBLE (-2375 1875);
FORCEPROP 1 LAST WATTAGE 1/16W
J 2
(-2625 1825);
DISPLAY 0.489362 (-2625 1825);
PAINT SKYBLUE (-2625 1825);
DISPLAY INVISIBLE (-2625 1825);
FORCEPROP 1 LAST PATH I2070
J 0
(-2600 2050);
DISPLAY 0.978723 (-2600 2050);
PAINT WHITE (-2600 2050);
DISPLAY INVISIBLE (-2600 2050);
FORCEPROP 2 LAST BOM_COST MEM
J 2
(-2525 2050);
DISPLAY 0.744681 (-2525 2050);
PAINT WHITE (-2525 2050);
DISPLAY INVISIBLE (-2525 2050);
FORCEPROP 2 LAST CDS_LIB pure_quanta
J 0
(-2550 1900);
DISPLAY INVISIBLE (-2550 1900);
FORCEADD Q_RES..1
(-2550 1850);
FORCEPROP 1 LAST LOCATION R1291
J 0
(-2450 1850);
DISPLAY 0.489362 (-2450 1850);
PAINT SKYBLUE (-2450 1850);
FORCEPROP 0 LAST $SEC 1
J 0
(-2450 1900);
DISPLAY 0.680851 (-2450 1900);
PAINT MONO (-2450 1900);
DISPLAY INVISIBLE (-2450 1900);
FORCEPROP 0 LAST CDS_SEC 1
J 0
(-2450 1900);
DISPLAY 0.680851 (-2450 1900);
DISPLAY INVISIBLE (-2450 1900);
FORCEPROP 1 LASTPIN (-2650 1850) $PN 1
J 0
(-2638 1862);
DISPLAY 0.489362 (-2638 1862);
PAINT MONO (-2638 1862);
FORCEPROP 1 LASTPIN (-2450 1850) $PN 2
J 0
(-2488 1862);
DISPLAY 0.489362 (-2488 1862);
PAINT MONO (-2488 1862);
FORCEPROP 1 LAST VALUE 33
J 2
(-2675 1850);
DISPLAY 0.489362 (-2675 1850);
PAINT SKYBLUE (-2675 1850);
FORCEPROP 2 LAST ROOM RST_CPU0_PLD_TO_DIMM
J 2
(-2525 1950);
DISPLAY 0.744681 (-2525 1950);
PAINT RED (-2525 1950);
DISPLAY INVISIBLE (-2525 1950);
FORCEPROP 1 LAST PACK_TYPE 0402LF
J 2
(-2375 1775);
DISPLAY 0.489362 (-2375 1775);
PAINT SKYBLUE (-2375 1775);
DISPLAY INVISIBLE (-2375 1775);
FORCEPROP 1 LAST PART_NUMBER CS03302JB29
J 2
(-2450 1900);
DISPLAY 0.489362 (-2450 1900);
PAINT SKYBLUE (-2450 1900);
DISPLAY INVISIBLE (-2450 1900);
FORCEPROP 1 LAST TOLERANCE 5%
J 0
(-2675 1825);
DISPLAY 0.489362 (-2675 1825);
PAINT SKYBLUE (-2675 1825);
DISPLAY INVISIBLE (-2675 1825);
FORCEPROP 1 LAST MATERIAL CHIP
J 2
(-2375 1825);
DISPLAY 0.489362 (-2375 1825);
PAINT SKYBLUE (-2375 1825);
DISPLAY INVISIBLE (-2375 1825);
FORCEPROP 1 LAST WATTAGE 1/16W
J 2
(-2625 1775);
DISPLAY 0.489362 (-2625 1775);
PAINT SKYBLUE (-2625 1775);
DISPLAY INVISIBLE (-2625 1775);
FORCEPROP 1 LAST PATH I2071
J 0
(-2600 2000);
DISPLAY 0.978723 (-2600 2000);
PAINT WHITE (-2600 2000);
DISPLAY INVISIBLE (-2600 2000);
FORCEPROP 2 LAST BOM_COST MEM
J 2
(-2525 2000);
DISPLAY 0.744681 (-2525 2000);
PAINT WHITE (-2525 2000);
DISPLAY INVISIBLE (-2525 2000);
FORCEPROP 2 LAST CDS_LIB pure_quanta
J 0
(-2550 1850);
DISPLAY INVISIBLE (-2550 1850);
FORCEADD Q_RES..1
(-2550 1650);
FORCEPROP 1 LAST LOCATION R274
J 0
(-2450 1650);
DISPLAY 0.489362 (-2450 1650);
PAINT SKYBLUE (-2450 1650);
FORCEPROP 0 LAST $SEC 1
J 0
(-2425 1700);
DISPLAY 0.680851 (-2425 1700);
PAINT MONO (-2425 1700);
DISPLAY INVISIBLE (-2425 1700);
FORCEPROP 0 LAST CDS_SEC 1
J 0
(-2425 1700);
DISPLAY 1.021277 (-2425 1700);
DISPLAY INVISIBLE (-2425 1700);
FORCEPROP 1 LASTPIN (-2650 1650) $PN 1
J 0
(-2638 1662);
DISPLAY 0.489362 (-2638 1662);
PAINT MONO (-2638 1662);
FORCEPROP 1 LASTPIN (-2450 1650) $PN 2
J 0
(-2488 1662);
DISPLAY 0.489362 (-2488 1662);
PAINT MONO (-2488 1662);
FORCEPROP 1 LAST VALUE 33
J 2
(-2675 1650);
DISPLAY 0.489362 (-2675 1650);
PAINT SKYBLUE (-2675 1650);
FORCEPROP 2 LAST ROOM RST_CPU0_PLD_TO_DIMM
J 2
(-2525 1750);
DISPLAY 0.744681 (-2525 1750);
PAINT RED (-2525 1750);
DISPLAY INVISIBLE (-2525 1750);
FORCEPROP 1 LAST PACK_TYPE 0402LF
J 2
(-2375 1575);
DISPLAY 0.489362 (-2375 1575);
PAINT SKYBLUE (-2375 1575);
DISPLAY INVISIBLE (-2375 1575);
FORCEPROP 1 LAST PART_NUMBER CS03302JB29
J 2
(-2450 1700);
DISPLAY 0.489362 (-2450 1700);
PAINT SKYBLUE (-2450 1700);
DISPLAY INVISIBLE (-2450 1700);
FORCEPROP 1 LAST TOLERANCE 5%
J 0
(-2675 1625);
DISPLAY 0.489362 (-2675 1625);
PAINT SKYBLUE (-2675 1625);
DISPLAY INVISIBLE (-2675 1625);
FORCEPROP 1 LAST MATERIAL CHIP
J 2
(-2375 1625);
DISPLAY 0.489362 (-2375 1625);
PAINT SKYBLUE (-2375 1625);
DISPLAY INVISIBLE (-2375 1625);
FORCEPROP 1 LAST WATTAGE 1/16W
J 2
(-2625 1575);
DISPLAY 0.489362 (-2625 1575);
PAINT SKYBLUE (-2625 1575);
DISPLAY INVISIBLE (-2625 1575);
FORCEPROP 1 LAST PATH I2072
J 0
(-2600 1800);
DISPLAY 0.978723 (-2600 1800);
PAINT WHITE (-2600 1800);
DISPLAY INVISIBLE (-2600 1800);
FORCEPROP 2 LAST CDS_LIB pure_quanta
J 0
(-2550 1650);
DISPLAY INVISIBLE (-2550 1650);
FORCEPROP 2 LAST BOM_COST MEM
J 2
(-2525 1800);
DISPLAY 0.744681 (-2525 1800);
PAINT WHITE (-2525 1800);
DISPLAY INVISIBLE (-2525 1800);
FORCEADD Q_RES..1
(-2550 1700);
FORCEPROP 1 LAST LOCATION R797
J 0
(-2450 1700);
DISPLAY 0.489362 (-2450 1700);
PAINT SKYBLUE (-2450 1700);
FORCEPROP 0 LAST $SEC 1
J 0
(-2425 1750);
DISPLAY 0.680851 (-2425 1750);
PAINT MONO (-2425 1750);
DISPLAY INVISIBLE (-2425 1750);
FORCEPROP 0 LAST CDS_SEC 1
J 0
(-2425 1750);
DISPLAY 1.021277 (-2425 1750);
DISPLAY INVISIBLE (-2425 1750);
FORCEPROP 1 LASTPIN (-2650 1700) $PN 1
J 0
(-2638 1712);
DISPLAY 0.489362 (-2638 1712);
PAINT MONO (-2638 1712);
FORCEPROP 1 LASTPIN (-2450 1700) $PN 2
J 0
(-2488 1712);
DISPLAY 0.489362 (-2488 1712);
PAINT MONO (-2488 1712);
FORCEPROP 1 LAST VALUE 33
J 2
(-2675 1700);
DISPLAY 0.489362 (-2675 1700);
PAINT SKYBLUE (-2675 1700);
FORCEPROP 2 LAST ROOM RST_CPU0_PLD_TO_DIMM
J 2
(-2525 1800);
DISPLAY 0.744681 (-2525 1800);
PAINT RED (-2525 1800);
DISPLAY INVISIBLE (-2525 1800);
FORCEPROP 1 LAST PACK_TYPE 0402LF
J 2
(-2375 1625);
DISPLAY 0.489362 (-2375 1625);
PAINT SKYBLUE (-2375 1625);
DISPLAY INVISIBLE (-2375 1625);
FORCEPROP 1 LAST PART_NUMBER CS03302JB29
J 2
(-2450 1750);
DISPLAY 0.489362 (-2450 1750);
PAINT SKYBLUE (-2450 1750);
DISPLAY INVISIBLE (-2450 1750);
FORCEPROP 1 LAST TOLERANCE 5%
J 0
(-2675 1675);
DISPLAY 0.489362 (-2675 1675);
PAINT SKYBLUE (-2675 1675);
DISPLAY INVISIBLE (-2675 1675);
FORCEPROP 1 LAST MATERIAL CHIP
J 2
(-2375 1675);
DISPLAY 0.489362 (-2375 1675);
PAINT SKYBLUE (-2375 1675);
DISPLAY INVISIBLE (-2375 1675);
FORCEPROP 1 LAST WATTAGE 1/16W
J 2
(-2625 1625);
DISPLAY 0.489362 (-2625 1625);
PAINT SKYBLUE (-2625 1625);
DISPLAY INVISIBLE (-2625 1625);
FORCEPROP 1 LAST PATH I2073
J 0
(-2600 1850);
DISPLAY 0.978723 (-2600 1850);
PAINT WHITE (-2600 1850);
DISPLAY INVISIBLE (-2600 1850);
FORCEPROP 2 LAST BOM_COST MEM
J 2
(-2525 1850);
DISPLAY 0.744681 (-2525 1850);
PAINT WHITE (-2525 1850);
DISPLAY INVISIBLE (-2525 1850);
FORCEPROP 2 LAST CDS_LIB pure_quanta
J 0
(-2550 1700);
DISPLAY INVISIBLE (-2550 1700);
FORCEADD Q_RES..1
(-2550 1300);
FORCEPROP 1 LAST LOCATION R799
J 0
(-2450 1300);
DISPLAY 0.489362 (-2450 1300);
PAINT SKYBLUE (-2450 1300);
FORCEPROP 0 LAST $SEC 1
J 0
(-2425 1350);
DISPLAY 0.680851 (-2425 1350);
PAINT MONO (-2425 1350);
DISPLAY INVISIBLE (-2425 1350);
FORCEPROP 0 LAST CDS_SEC 1
J 0
(-2425 1350);
DISPLAY 1.021277 (-2425 1350);
DISPLAY INVISIBLE (-2425 1350);
FORCEPROP 1 LASTPIN (-2650 1300) $PN 1
J 0
(-2638 1312);
DISPLAY 0.489362 (-2638 1312);
PAINT MONO (-2638 1312);
FORCEPROP 1 LASTPIN (-2450 1300) $PN 2
J 0
(-2488 1312);
DISPLAY 0.489362 (-2488 1312);
PAINT MONO (-2488 1312);
FORCEPROP 1 LAST VALUE 33
J 2
(-2675 1300);
DISPLAY 0.489362 (-2675 1300);
PAINT SKYBLUE (-2675 1300);
FORCEPROP 2 LAST ROOM RST_CPU0_PLD_TO_DIMM
J 2
(-2525 1400);
DISPLAY 0.744681 (-2525 1400);
PAINT RED (-2525 1400);
DISPLAY INVISIBLE (-2525 1400);
FORCEPROP 1 LAST PACK_TYPE 0402LF
J 2
(-2375 1225);
DISPLAY 0.489362 (-2375 1225);
PAINT SKYBLUE (-2375 1225);
DISPLAY INVISIBLE (-2375 1225);
FORCEPROP 1 LAST PART_NUMBER CS03302JB29
J 2
(-2450 1350);
DISPLAY 0.489362 (-2450 1350);
PAINT SKYBLUE (-2450 1350);
DISPLAY INVISIBLE (-2450 1350);
FORCEPROP 1 LAST TOLERANCE 5%
J 0
(-2675 1275);
DISPLAY 0.489362 (-2675 1275);
PAINT SKYBLUE (-2675 1275);
DISPLAY INVISIBLE (-2675 1275);
FORCEPROP 1 LAST MATERIAL CHIP
J 2
(-2375 1275);
DISPLAY 0.489362 (-2375 1275);
PAINT SKYBLUE (-2375 1275);
DISPLAY INVISIBLE (-2375 1275);
FORCEPROP 1 LAST WATTAGE 1/16W
J 2
(-2625 1225);
DISPLAY 0.489362 (-2625 1225);
PAINT SKYBLUE (-2625 1225);
DISPLAY INVISIBLE (-2625 1225);
FORCEPROP 1 LAST PATH I2074
J 0
(-2600 1450);
DISPLAY 0.978723 (-2600 1450);
PAINT WHITE (-2600 1450);
DISPLAY INVISIBLE (-2600 1450);
FORCEPROP 2 LAST CDS_LIB pure_quanta
J 0
(-2550 1300);
DISPLAY INVISIBLE (-2550 1300);
FORCEPROP 2 LAST BOM_COST MEM
J 2
(-2525 1450);
DISPLAY 0.744681 (-2525 1450);
PAINT WHITE (-2525 1450);
DISPLAY INVISIBLE (-2525 1450);
FORCEADD Q_RES..1
(-2550 1450);
FORCEPROP 1 LAST LOCATION R798
J 0
(-2450 1450);
DISPLAY 0.489362 (-2450 1450);
PAINT SKYBLUE (-2450 1450);
FORCEPROP 0 LAST $SEC 1
J 0
(-2425 1500);
DISPLAY 0.680851 (-2425 1500);
PAINT MONO (-2425 1500);
DISPLAY INVISIBLE (-2425 1500);
FORCEPROP 0 LAST CDS_SEC 1
J 0
(-2425 1500);
DISPLAY 1.021277 (-2425 1500);
DISPLAY INVISIBLE (-2425 1500);
FORCEPROP 1 LASTPIN (-2650 1450) $PN 1
J 0
(-2638 1462);
DISPLAY 0.489362 (-2638 1462);
PAINT MONO (-2638 1462);
FORCEPROP 1 LASTPIN (-2450 1450) $PN 2
J 0
(-2488 1462);
DISPLAY 0.489362 (-2488 1462);
PAINT MONO (-2488 1462);
FORCEPROP 1 LAST VALUE 33
J 2
(-2675 1450);
DISPLAY 0.489362 (-2675 1450);
PAINT SKYBLUE (-2675 1450);
FORCEPROP 2 LAST ROOM RST_CPU0_PLD_TO_DIMM
J 2
(-2525 1550);
DISPLAY 0.744681 (-2525 1550);
PAINT RED (-2525 1550);
DISPLAY INVISIBLE (-2525 1550);
FORCEPROP 1 LAST PACK_TYPE 0402LF
J 2
(-2375 1375);
DISPLAY 0.489362 (-2375 1375);
PAINT SKYBLUE (-2375 1375);
DISPLAY INVISIBLE (-2375 1375);
FORCEPROP 1 LAST PART_NUMBER CS03302JB29
J 2
(-2450 1500);
DISPLAY 0.489362 (-2450 1500);
PAINT SKYBLUE (-2450 1500);
DISPLAY INVISIBLE (-2450 1500);
FORCEPROP 1 LAST TOLERANCE 5%
J 0
(-2675 1425);
DISPLAY 0.489362 (-2675 1425);
PAINT SKYBLUE (-2675 1425);
DISPLAY INVISIBLE (-2675 1425);
FORCEPROP 1 LAST MATERIAL CHIP
J 2
(-2375 1425);
DISPLAY 0.489362 (-2375 1425);
PAINT SKYBLUE (-2375 1425);
DISPLAY INVISIBLE (-2375 1425);
FORCEPROP 1 LAST WATTAGE 1/16W
J 2
(-2625 1375);
DISPLAY 0.489362 (-2625 1375);
PAINT SKYBLUE (-2625 1375);
DISPLAY INVISIBLE (-2625 1375);
FORCEPROP 1 LAST PATH I2075
J 0
(-2600 1600);
DISPLAY 0.978723 (-2600 1600);
PAINT WHITE (-2600 1600);
DISPLAY INVISIBLE (-2600 1600);
FORCEPROP 2 LAST BOM_COST MEM
J 2
(-2525 1600);
DISPLAY 0.744681 (-2525 1600);
PAINT WHITE (-2525 1600);
DISPLAY INVISIBLE (-2525 1600);
FORCEPROP 2 LAST CDS_LIB pure_quanta
J 0
(-2550 1450);
DISPLAY INVISIBLE (-2550 1450);
FORCEADD Q_RES..1
(-2550 1100);
FORCEPROP 1 LAST LOCATION R86
J 0
(-2450 1100);
DISPLAY 0.489362 (-2450 1100);
PAINT SKYBLUE (-2450 1100);
FORCEPROP 2 LAST $SEC 1
J 0
(-2600 1300);
DISPLAY 0.680851 (-2600 1300);
PAINT MONO (-2600 1300);
DISPLAY INVISIBLE (-2600 1300);
FORCEPROP 2 LAST CDS_SEC 1
J 0
(-2600 1300);
DISPLAY 1.021277 (-2600 1300);
DISPLAY INVISIBLE (-2600 1300);
FORCEPROP 1 LASTPIN (-2650 1100) $PN 1
J 0
(-2638 1112);
DISPLAY 0.489362 (-2638 1112);
PAINT MONO (-2638 1112);
FORCEPROP 1 LASTPIN (-2450 1100) $PN 2
J 0
(-2488 1112);
DISPLAY 0.489362 (-2488 1112);
PAINT MONO (-2488 1112);
FORCEPROP 1 LAST VALUE 33
J 2
(-2675 1100);
DISPLAY 0.489362 (-2675 1100);
PAINT SKYBLUE (-2675 1100);
FORCEPROP 2 LAST ROOM RST_CPU0_PLD_TO_DIMM
J 2
(-2525 1200);
DISPLAY 0.744681 (-2525 1200);
PAINT RED (-2525 1200);
DISPLAY INVISIBLE (-2525 1200);
FORCEPROP 1 LAST PACK_TYPE 0402LF
J 2
(-2375 1025);
DISPLAY 0.489362 (-2375 1025);
PAINT SKYBLUE (-2375 1025);
DISPLAY INVISIBLE (-2375 1025);
FORCEPROP 1 LAST PART_NUMBER CS03302JB29
J 2
(-2450 1150);
DISPLAY 0.489362 (-2450 1150);
PAINT SKYBLUE (-2450 1150);
DISPLAY INVISIBLE (-2450 1150);
FORCEPROP 1 LAST TOLERANCE 5%
J 0
(-2675 1075);
DISPLAY 0.489362 (-2675 1075);
PAINT SKYBLUE (-2675 1075);
DISPLAY INVISIBLE (-2675 1075);
FORCEPROP 1 LAST MATERIAL CHIP
J 2
(-2375 1075);
DISPLAY 0.489362 (-2375 1075);
PAINT SKYBLUE (-2375 1075);
DISPLAY INVISIBLE (-2375 1075);
FORCEPROP 1 LAST WATTAGE 1/16W
J 2
(-2625 1025);
DISPLAY 0.489362 (-2625 1025);
PAINT SKYBLUE (-2625 1025);
DISPLAY INVISIBLE (-2625 1025);
FORCEPROP 1 LAST PATH I2076
J 0
(-2600 1250);
DISPLAY 0.978723 (-2600 1250);
PAINT WHITE (-2600 1250);
DISPLAY INVISIBLE (-2600 1250);
FORCEPROP 2 LAST CDS_LIB pure_quanta
J 0
(-2550 1100);
DISPLAY INVISIBLE (-2550 1100);
FORCEPROP 2 LAST BOM_COST MEM
J 2
(-2525 1250);
DISPLAY 0.744681 (-2525 1250);
PAINT WHITE (-2525 1250);
DISPLAY INVISIBLE (-2525 1250);
FORCEADD Q_RES..1
(-2550 1200);
FORCEPROP 1 LAST LOCATION R560
J 0
(-2450 1200);
DISPLAY 0.489362 (-2450 1200);
PAINT SKYBLUE (-2450 1200);
FORCEPROP 0 LAST $SEC 1
J 0
(-2425 1250);
DISPLAY 0.680851 (-2425 1250);
PAINT MONO (-2425 1250);
DISPLAY INVISIBLE (-2425 1250);
FORCEPROP 0 LAST CDS_SEC 1
J 0
(-2425 1250);
DISPLAY 1.021277 (-2425 1250);
DISPLAY INVISIBLE (-2425 1250);
FORCEPROP 1 LASTPIN (-2650 1200) $PN 1
J 0
(-2638 1212);
DISPLAY 0.489362 (-2638 1212);
PAINT MONO (-2638 1212);
FORCEPROP 1 LASTPIN (-2450 1200) $PN 2
J 0
(-2488 1212);
DISPLAY 0.489362 (-2488 1212);
PAINT MONO (-2488 1212);
FORCEPROP 1 LAST VALUE 33
J 2
(-2675 1200);
DISPLAY 0.489362 (-2675 1200);
PAINT SKYBLUE (-2675 1200);
FORCEPROP 2 LAST ROOM RST_CPU0_PLD_TO_DIMM
J 2
(-2525 1300);
DISPLAY 0.744681 (-2525 1300);
PAINT RED (-2525 1300);
DISPLAY INVISIBLE (-2525 1300);
FORCEPROP 1 LAST PACK_TYPE 0402LF
J 2
(-2375 1125);
DISPLAY 0.489362 (-2375 1125);
PAINT SKYBLUE (-2375 1125);
DISPLAY INVISIBLE (-2375 1125);
FORCEPROP 1 LAST PART_NUMBER CS03302JB29
J 2
(-2450 1250);
DISPLAY 0.489362 (-2450 1250);
PAINT SKYBLUE (-2450 1250);
DISPLAY INVISIBLE (-2450 1250);
FORCEPROP 1 LAST TOLERANCE 5%
J 0
(-2675 1175);
DISPLAY 0.489362 (-2675 1175);
PAINT SKYBLUE (-2675 1175);
DISPLAY INVISIBLE (-2675 1175);
FORCEPROP 1 LAST MATERIAL CHIP
J 2
(-2375 1175);
DISPLAY 0.489362 (-2375 1175);
PAINT SKYBLUE (-2375 1175);
DISPLAY INVISIBLE (-2375 1175);
FORCEPROP 1 LAST WATTAGE 1/16W
J 2
(-2625 1125);
DISPLAY 0.489362 (-2625 1125);
PAINT SKYBLUE (-2625 1125);
DISPLAY INVISIBLE (-2625 1125);
FORCEPROP 1 LAST PATH I2077
J 0
(-2600 1350);
DISPLAY 0.978723 (-2600 1350);
PAINT WHITE (-2600 1350);
DISPLAY INVISIBLE (-2600 1350);
FORCEPROP 2 LAST BOM_COST MEM
J 2
(-2525 1350);
DISPLAY 0.744681 (-2525 1350);
PAINT WHITE (-2525 1350);
DISPLAY INVISIBLE (-2525 1350);
FORCEPROP 2 LAST CDS_LIB pure_quanta
J 0
(-2550 1200);
DISPLAY INVISIBLE (-2550 1200);
FORCEADD Q_RES..1
(-2550 850);
FORCEPROP 1 LAST LOCATION R162
J 0
(-2450 850);
DISPLAY 0.489362 (-2450 850);
PAINT SKYBLUE (-2450 850);
FORCEPROP 0 LAST $SEC 1
J 0
(-2425 900);
DISPLAY 0.680851 (-2425 900);
PAINT MONO (-2425 900);
DISPLAY INVISIBLE (-2425 900);
FORCEPROP 0 LAST CDS_SEC 1
J 0
(-2425 900);
DISPLAY 1.021277 (-2425 900);
DISPLAY INVISIBLE (-2425 900);
FORCEPROP 1 LASTPIN (-2650 850) $PN 1
J 0
(-2638 862);
DISPLAY 0.489362 (-2638 862);
PAINT MONO (-2638 862);
FORCEPROP 1 LASTPIN (-2450 850) $PN 2
J 0
(-2488 862);
DISPLAY 0.489362 (-2488 862);
PAINT MONO (-2488 862);
FORCEPROP 1 LAST VALUE 33
J 2
(-2675 850);
DISPLAY 0.489362 (-2675 850);
PAINT SKYBLUE (-2675 850);
FORCEPROP 2 LAST ROOM RST_CPU0_PLD_TO_DIMM
J 2
(-2525 950);
DISPLAY 0.744681 (-2525 950);
PAINT RED (-2525 950);
DISPLAY INVISIBLE (-2525 950);
FORCEPROP 1 LAST PACK_TYPE 0402LF
J 2
(-2375 775);
DISPLAY 0.489362 (-2375 775);
PAINT SKYBLUE (-2375 775);
DISPLAY INVISIBLE (-2375 775);
FORCEPROP 1 LAST PART_NUMBER CS03302JB29
J 2
(-2450 900);
DISPLAY 0.489362 (-2450 900);
PAINT SKYBLUE (-2450 900);
DISPLAY INVISIBLE (-2450 900);
FORCEPROP 1 LAST TOLERANCE 5%
J 0
(-2675 825);
DISPLAY 0.489362 (-2675 825);
PAINT SKYBLUE (-2675 825);
DISPLAY INVISIBLE (-2675 825);
FORCEPROP 1 LAST MATERIAL CHIP
J 2
(-2375 825);
DISPLAY 0.489362 (-2375 825);
PAINT SKYBLUE (-2375 825);
DISPLAY INVISIBLE (-2375 825);
FORCEPROP 1 LAST WATTAGE 1/16W
J 2
(-2625 775);
DISPLAY 0.489362 (-2625 775);
PAINT SKYBLUE (-2625 775);
DISPLAY INVISIBLE (-2625 775);
FORCEPROP 1 LAST PATH I2078
J 0
(-2600 1000);
DISPLAY 0.978723 (-2600 1000);
PAINT WHITE (-2600 1000);
DISPLAY INVISIBLE (-2600 1000);
FORCEPROP 2 LAST CDS_LIB pure_quanta
J 0
(-2550 850);
DISPLAY INVISIBLE (-2550 850);
FORCEPROP 2 LAST BOM_COST MEM
J 2
(-2525 1000);
DISPLAY 0.744681 (-2525 1000);
PAINT WHITE (-2525 1000);
DISPLAY INVISIBLE (-2525 1000);
FORCEADD Q_RES..1
(-2550 900);
FORCEPROP 1 LAST LOCATION R439
J 0
(-2450 900);
DISPLAY 0.489362 (-2450 900);
PAINT SKYBLUE (-2450 900);
FORCEPROP 0 LAST $SEC 1
J 0
(-2425 950);
DISPLAY 0.680851 (-2425 950);
PAINT MONO (-2425 950);
DISPLAY INVISIBLE (-2425 950);
FORCEPROP 0 LAST CDS_SEC 1
J 0
(-2425 950);
DISPLAY 1.021277 (-2425 950);
DISPLAY INVISIBLE (-2425 950);
FORCEPROP 1 LASTPIN (-2650 900) $PN 1
J 0
(-2638 912);
DISPLAY 0.489362 (-2638 912);
PAINT MONO (-2638 912);
FORCEPROP 1 LASTPIN (-2450 900) $PN 2
J 0
(-2488 912);
DISPLAY 0.489362 (-2488 912);
PAINT MONO (-2488 912);
FORCEPROP 1 LAST VALUE 33
J 2
(-2675 900);
DISPLAY 0.489362 (-2675 900);
PAINT SKYBLUE (-2675 900);
FORCEPROP 2 LAST ROOM RST_CPU0_PLD_TO_DIMM
J 2
(-2525 1000);
DISPLAY 0.744681 (-2525 1000);
PAINT RED (-2525 1000);
DISPLAY INVISIBLE (-2525 1000);
FORCEPROP 1 LAST PACK_TYPE 0402LF
J 2
(-2375 825);
DISPLAY 0.489362 (-2375 825);
PAINT SKYBLUE (-2375 825);
DISPLAY INVISIBLE (-2375 825);
FORCEPROP 1 LAST PART_NUMBER CS03302JB29
J 2
(-2450 950);
DISPLAY 0.489362 (-2450 950);
PAINT SKYBLUE (-2450 950);
DISPLAY INVISIBLE (-2450 950);
FORCEPROP 1 LAST TOLERANCE 5%
J 0
(-2675 875);
DISPLAY 0.489362 (-2675 875);
PAINT SKYBLUE (-2675 875);
DISPLAY INVISIBLE (-2675 875);
FORCEPROP 1 LAST MATERIAL CHIP
J 2
(-2375 875);
DISPLAY 0.489362 (-2375 875);
PAINT SKYBLUE (-2375 875);
DISPLAY INVISIBLE (-2375 875);
FORCEPROP 1 LAST WATTAGE 1/16W
J 2
(-2625 825);
DISPLAY 0.489362 (-2625 825);
PAINT SKYBLUE (-2625 825);
DISPLAY INVISIBLE (-2625 825);
FORCEPROP 1 LAST PATH I2079
J 0
(-2600 1050);
DISPLAY 0.978723 (-2600 1050);
PAINT WHITE (-2600 1050);
DISPLAY INVISIBLE (-2600 1050);
FORCEPROP 2 LAST BOM_COST MEM
J 2
(-2525 1050);
DISPLAY 0.744681 (-2525 1050);
PAINT WHITE (-2525 1050);
DISPLAY INVISIBLE (-2525 1050);
FORCEPROP 2 LAST CDS_LIB pure_quanta
J 0
(-2550 900);
DISPLAY INVISIBLE (-2550 900);
FORCEADD Q_RES..1
(-2550 650);
FORCEPROP 1 LAST LOCATION R85
J 0
(-2450 650);
DISPLAY 0.489362 (-2450 650);
PAINT SKYBLUE (-2450 650);
FORCEPROP 2 LAST $SEC 1
J 0
(-2600 850);
DISPLAY 0.680851 (-2600 850);
PAINT MONO (-2600 850);
DISPLAY INVISIBLE (-2600 850);
FORCEPROP 2 LAST CDS_SEC 1
J 0
(-2600 850);
DISPLAY 1.021277 (-2600 850);
DISPLAY INVISIBLE (-2600 850);
FORCEPROP 1 LASTPIN (-2650 650) $PN 1
J 0
(-2638 662);
DISPLAY 0.489362 (-2638 662);
PAINT MONO (-2638 662);
FORCEPROP 1 LASTPIN (-2450 650) $PN 2
J 0
(-2488 662);
DISPLAY 0.489362 (-2488 662);
PAINT MONO (-2488 662);
FORCEPROP 1 LAST VALUE 33
J 2
(-2675 650);
DISPLAY 0.489362 (-2675 650);
PAINT SKYBLUE (-2675 650);
FORCEPROP 2 LAST ROOM RST_CPU0_PLD_TO_DIMM
J 2
(-2525 750);
DISPLAY 0.744681 (-2525 750);
PAINT RED (-2525 750);
DISPLAY INVISIBLE (-2525 750);
FORCEPROP 1 LAST PACK_TYPE 0402LF
J 2
(-2375 575);
DISPLAY 0.489362 (-2375 575);
PAINT SKYBLUE (-2375 575);
DISPLAY INVISIBLE (-2375 575);
FORCEPROP 1 LAST PART_NUMBER CS03302JB29
J 2
(-2450 700);
DISPLAY 0.489362 (-2450 700);
PAINT SKYBLUE (-2450 700);
DISPLAY INVISIBLE (-2450 700);
FORCEPROP 1 LAST TOLERANCE 5%
J 0
(-2675 625);
DISPLAY 0.489362 (-2675 625);
PAINT SKYBLUE (-2675 625);
DISPLAY INVISIBLE (-2675 625);
FORCEPROP 1 LAST MATERIAL CHIP
J 2
(-2375 625);
DISPLAY 0.489362 (-2375 625);
PAINT SKYBLUE (-2375 625);
DISPLAY INVISIBLE (-2375 625);
FORCEPROP 1 LAST WATTAGE 1/16W
J 2
(-2625 575);
DISPLAY 0.489362 (-2625 575);
PAINT SKYBLUE (-2625 575);
DISPLAY INVISIBLE (-2625 575);
FORCEPROP 1 LAST PATH I2080
J 0
(-2600 800);
DISPLAY 0.978723 (-2600 800);
PAINT WHITE (-2600 800);
DISPLAY INVISIBLE (-2600 800);
FORCEPROP 2 LAST CDS_LIB pure_quanta
J 0
(-2550 650);
DISPLAY INVISIBLE (-2550 650);
FORCEPROP 2 LAST BOM_COST MEM
J 2
(-2525 800);
DISPLAY 0.744681 (-2525 800);
PAINT WHITE (-2525 800);
DISPLAY INVISIBLE (-2525 800);
FORCEADD Q_RES..1
(-6500 2900);
FORCEPROP 1 LAST LOCATION R229
J 0
(-6375 2900);
DISPLAY 0.489362 (-6375 2900);
PAINT SKYBLUE (-6375 2900);
FORCEPROP 0 LAST $SEC 1
J 2
(-6375 2950);
DISPLAY 0.680851 (-6375 2950);
PAINT MONO (-6375 2950);
DISPLAY INVISIBLE (-6375 2950);
FORCEPROP 0 LAST CDS_SEC 1
J 2
(-6375 2950);
DISPLAY 1.021277 (-6375 2950);
DISPLAY INVISIBLE (-6375 2950);
FORCEPROP 1 LASTPIN (-6600 2900) $PN 1
J 0
(-6588 2912);
DISPLAY 0.489362 (-6588 2912);
PAINT MONO (-6588 2912);
FORCEPROP 1 LASTPIN (-6400 2900) $PN 2
J 0
(-6438 2912);
DISPLAY 0.489362 (-6438 2912);
PAINT MONO (-6438 2912);
FORCEPROP 1 LAST VALUE 33
J 2
(-6625 2900);
DISPLAY 0.489362 (-6625 2900);
PAINT SKYBLUE (-6625 2900);
FORCEPROP 2 LAST ROOM RST_CPU0_PLD_TO_DIMM
J 2
(-6475 3000);
DISPLAY 0.744681 (-6475 3000);
PAINT RED (-6475 3000);
DISPLAY INVISIBLE (-6475 3000);
FORCEPROP 1 LAST PACK_TYPE 0402LF
J 2
(-6325 2825);
DISPLAY 0.489362 (-6325 2825);
PAINT SKYBLUE (-6325 2825);
DISPLAY INVISIBLE (-6325 2825);
FORCEPROP 1 LAST PART_NUMBER CS03302JB29
J 2
(-6400 2950);
DISPLAY 0.489362 (-6400 2950);
PAINT SKYBLUE (-6400 2950);
DISPLAY INVISIBLE (-6400 2950);
FORCEPROP 1 LAST TOLERANCE 5%
J 0
(-6625 2875);
DISPLAY 0.489362 (-6625 2875);
PAINT SKYBLUE (-6625 2875);
DISPLAY INVISIBLE (-6625 2875);
FORCEPROP 1 LAST MATERIAL CHIP
J 2
(-6325 2875);
DISPLAY 0.489362 (-6325 2875);
PAINT SKYBLUE (-6325 2875);
DISPLAY INVISIBLE (-6325 2875);
FORCEPROP 1 LAST WATTAGE 1/16W
J 2
(-6575 2825);
DISPLAY 0.489362 (-6575 2825);
PAINT SKYBLUE (-6575 2825);
DISPLAY INVISIBLE (-6575 2825);
FORCEPROP 1 LAST PATH I2081
J 0
(-6550 3050);
DISPLAY 0.978723 (-6550 3050);
PAINT WHITE (-6550 3050);
DISPLAY INVISIBLE (-6550 3050);
FORCEPROP 2 LAST CDS_LIB pure_quanta
J 2
(-6500 2900);
DISPLAY INVISIBLE (-6500 2900);
FORCEPROP 2 LAST BOM_COST MEM
J 2
(-6475 3050);
DISPLAY 0.744681 (-6475 3050);
PAINT WHITE (-6475 3050);
DISPLAY INVISIBLE (-6475 3050);
FORCEADD Q_RES..1
(-6500 2950);
FORCEPROP 1 LAST LOCATION R669
J 0
(-6375 2950);
DISPLAY 0.489362 (-6375 2950);
PAINT SKYBLUE (-6375 2950);
FORCEPROP 2 LAST $SEC 1
J 2
(-6550 3150);
DISPLAY 0.680851 (-6550 3150);
PAINT MONO (-6550 3150);
DISPLAY INVISIBLE (-6550 3150);
FORCEPROP 2 LAST CDS_SEC 1
J 2
(-6550 3150);
DISPLAY 0.680851 (-6550 3150);
DISPLAY INVISIBLE (-6550 3150);
FORCEPROP 1 LASTPIN (-6600 2950) $PN 1
J 0
(-6588 2962);
DISPLAY 0.489362 (-6588 2962);
PAINT MONO (-6588 2962);
FORCEPROP 1 LASTPIN (-6400 2950) $PN 2
J 0
(-6438 2962);
DISPLAY 0.489362 (-6438 2962);
PAINT MONO (-6438 2962);
FORCEPROP 1 LAST VALUE 0
J 2
(-6625 2950);
DISPLAY 0.489362 (-6625 2950);
PAINT SKYBLUE (-6625 2950);
FORCEPROP 2 LAST ROOM RST_CPU0_PLD_TO_DIMM
J 2
(-6475 3050);
DISPLAY 0.744681 (-6475 3050);
PAINT RED (-6475 3050);
DISPLAY INVISIBLE (-6475 3050);
FORCEPROP 1 LAST PACK_TYPE 0402LF
J 2
(-6325 2875);
DISPLAY 0.489362 (-6325 2875);
PAINT SKYBLUE (-6325 2875);
DISPLAY INVISIBLE (-6325 2875);
FORCEPROP 1 LAST PART_NUMBER CS00002JB38
J 2
(-6400 3000);
DISPLAY 0.489362 (-6400 3000);
PAINT SKYBLUE (-6400 3000);
DISPLAY INVISIBLE (-6400 3000);
FORCEPROP 1 LAST TOLERANCE 5%
J 0
(-6625 2925);
DISPLAY 0.489362 (-6625 2925);
PAINT SKYBLUE (-6625 2925);
DISPLAY INVISIBLE (-6625 2925);
FORCEPROP 1 LAST MATERIAL CHIP
J 2
(-6325 2925);
DISPLAY 0.489362 (-6325 2925);
PAINT SKYBLUE (-6325 2925);
DISPLAY INVISIBLE (-6325 2925);
FORCEPROP 1 LAST WATTAGE 1/16W
J 2
(-6575 2875);
DISPLAY 0.489362 (-6575 2875);
PAINT SKYBLUE (-6575 2875);
DISPLAY INVISIBLE (-6575 2875);
FORCEPROP 1 LAST PATH I2082
J 0
(-6550 3100);
DISPLAY 0.978723 (-6550 3100);
PAINT WHITE (-6550 3100);
DISPLAY INVISIBLE (-6550 3100);
FORCEPROP 2 LAST CDS_LIB pure_quanta
J 2
(-6500 2950);
DISPLAY INVISIBLE (-6500 2950);
FORCEPROP 2 LAST BOM_COST MEM
J 2
(-6475 3100);
DISPLAY 0.744681 (-6475 3100);
PAINT WHITE (-6475 3100);
DISPLAY INVISIBLE (-6475 3100);
FORCEADD Q_RES..1
(-6500 3000);
FORCEPROP 1 LAST LOCATION R667
J 0
(-6375 3000);
DISPLAY 0.489362 (-6375 3000);
PAINT SKYBLUE (-6375 3000);
FORCEPROP 2 LAST $SEC 1
J 2
(-6550 3200);
DISPLAY 0.680851 (-6550 3200);
PAINT MONO (-6550 3200);
DISPLAY INVISIBLE (-6550 3200);
FORCEPROP 2 LAST CDS_SEC 1
J 2
(-6550 3200);
DISPLAY 0.680851 (-6550 3200);
DISPLAY INVISIBLE (-6550 3200);
FORCEPROP 1 LASTPIN (-6600 3000) $PN 1
J 0
(-6588 3012);
DISPLAY 0.489362 (-6588 3012);
PAINT MONO (-6588 3012);
FORCEPROP 1 LASTPIN (-6400 3000) $PN 2
J 0
(-6438 3012);
DISPLAY 0.489362 (-6438 3012);
PAINT MONO (-6438 3012);
FORCEPROP 1 LAST VALUE 0
J 2
(-6625 3000);
DISPLAY 0.489362 (-6625 3000);
PAINT SKYBLUE (-6625 3000);
FORCEPROP 2 LAST ROOM RST_CPU0_PLD_TO_DIMM
J 2
(-6475 3100);
DISPLAY 0.744681 (-6475 3100);
PAINT RED (-6475 3100);
DISPLAY INVISIBLE (-6475 3100);
FORCEPROP 1 LAST PACK_TYPE 0402LF
J 2
(-6325 2925);
DISPLAY 0.489362 (-6325 2925);
PAINT SKYBLUE (-6325 2925);
DISPLAY INVISIBLE (-6325 2925);
FORCEPROP 1 LAST PART_NUMBER CS00002JB38
J 2
(-6400 3050);
DISPLAY 0.489362 (-6400 3050);
PAINT SKYBLUE (-6400 3050);
DISPLAY INVISIBLE (-6400 3050);
FORCEPROP 1 LAST TOLERANCE 5%
J 0
(-6625 2975);
DISPLAY 0.489362 (-6625 2975);
PAINT SKYBLUE (-6625 2975);
DISPLAY INVISIBLE (-6625 2975);
FORCEPROP 1 LAST MATERIAL CHIP
J 2
(-6325 2975);
DISPLAY 0.489362 (-6325 2975);
PAINT SKYBLUE (-6325 2975);
DISPLAY INVISIBLE (-6325 2975);
FORCEPROP 1 LAST WATTAGE 1/16W
J 2
(-6575 2925);
DISPLAY 0.489362 (-6575 2925);
PAINT SKYBLUE (-6575 2925);
DISPLAY INVISIBLE (-6575 2925);
FORCEPROP 1 LAST PATH I2083
J 0
(-6550 3150);
DISPLAY 0.978723 (-6550 3150);
PAINT WHITE (-6550 3150);
DISPLAY INVISIBLE (-6550 3150);
FORCEPROP 2 LAST CDS_LIB pure_quanta
J 2
(-6500 3000);
DISPLAY INVISIBLE (-6500 3000);
FORCEPROP 2 LAST BOM_COST MEM
J 2
(-6475 3150);
DISPLAY 0.744681 (-6475 3150);
PAINT WHITE (-6475 3150);
DISPLAY INVISIBLE (-6475 3150);
FORCEADD Q_RES..1
(-6500 2850);
FORCEPROP 1 LAST LOCATION R230
J 0
(-6375 2850);
DISPLAY 0.489362 (-6375 2850);
PAINT SKYBLUE (-6375 2850);
FORCEPROP 0 LAST $SEC 1
J 0
(-6375 2900);
DISPLAY 0.680851 (-6375 2900);
PAINT MONO (-6375 2900);
DISPLAY INVISIBLE (-6375 2900);
FORCEPROP 0 LAST CDS_SEC 1
J 0
(-6375 2900);
DISPLAY 1.021277 (-6375 2900);
DISPLAY INVISIBLE (-6375 2900);
FORCEPROP 1 LASTPIN (-6600 2850) $PN 1
J 0
(-6588 2862);
DISPLAY 0.489362 (-6588 2862);
PAINT MONO (-6588 2862);
FORCEPROP 1 LASTPIN (-6400 2850) $PN 2
J 0
(-6438 2862);
DISPLAY 0.489362 (-6438 2862);
PAINT MONO (-6438 2862);
FORCEPROP 1 LAST VALUE 0
J 2
(-6625 2850);
DISPLAY 0.489362 (-6625 2850);
PAINT SKYBLUE (-6625 2850);
FORCEPROP 2 LAST ROOM RST_CPU0_PLD_TO_DIMM
J 2
(-6475 2950);
DISPLAY 0.744681 (-6475 2950);
PAINT RED (-6475 2950);
DISPLAY INVISIBLE (-6475 2950);
FORCEPROP 1 LAST PACK_TYPE 0402LF
J 2
(-6325 2775);
DISPLAY 0.489362 (-6325 2775);
PAINT SKYBLUE (-6325 2775);
DISPLAY INVISIBLE (-6325 2775);
FORCEPROP 1 LAST PART_NUMBER CS00002JB38
J 2
(-6400 2900);
DISPLAY 0.489362 (-6400 2900);
PAINT SKYBLUE (-6400 2900);
DISPLAY INVISIBLE (-6400 2900);
FORCEPROP 1 LAST TOLERANCE 5%
J 0
(-6625 2825);
DISPLAY 0.489362 (-6625 2825);
PAINT SKYBLUE (-6625 2825);
DISPLAY INVISIBLE (-6625 2825);
FORCEPROP 1 LAST MATERIAL CHIP
J 2
(-6325 2825);
DISPLAY 0.489362 (-6325 2825);
PAINT SKYBLUE (-6325 2825);
DISPLAY INVISIBLE (-6325 2825);
FORCEPROP 1 LAST WATTAGE 1/16W
J 2
(-6575 2775);
DISPLAY 0.489362 (-6575 2775);
PAINT SKYBLUE (-6575 2775);
DISPLAY INVISIBLE (-6575 2775);
FORCEPROP 1 LAST PATH I2084
J 0
(-6550 3000);
DISPLAY 0.978723 (-6550 3000);
PAINT WHITE (-6550 3000);
DISPLAY INVISIBLE (-6550 3000);
FORCEPROP 2 LAST BOM_COST MEM
J 2
(-6475 3000);
DISPLAY 0.744681 (-6475 3000);
PAINT WHITE (-6475 3000);
DISPLAY INVISIBLE (-6475 3000);
FORCEPROP 2 LAST CDS_LIB pure_quanta
J 2
(-6500 2850);
DISPLAY INVISIBLE (-6500 2850);
FORCEADD Q_RES..1
(-6500 2650);
FORCEPROP 1 LAST LOCATION R208
J 0
(-6375 2650);
DISPLAY 0.489362 (-6375 2650);
PAINT SKYBLUE (-6375 2650);
FORCEPROP 0 LAST $SEC 1
J 0
(-6375 2700);
DISPLAY 0.680851 (-6375 2700);
PAINT MONO (-6375 2700);
DISPLAY INVISIBLE (-6375 2700);
FORCEPROP 0 LAST CDS_SEC 1
J 0
(-6375 2700);
DISPLAY 1.021277 (-6375 2700);
DISPLAY INVISIBLE (-6375 2700);
FORCEPROP 1 LASTPIN (-6600 2650) $PN 1
J 0
(-6588 2662);
DISPLAY 0.489362 (-6588 2662);
PAINT MONO (-6588 2662);
FORCEPROP 1 LASTPIN (-6400 2650) $PN 2
J 0
(-6438 2662);
DISPLAY 0.489362 (-6438 2662);
PAINT MONO (-6438 2662);
FORCEPROP 1 LAST VALUE 33
J 2
(-6625 2650);
DISPLAY 0.489362 (-6625 2650);
PAINT SKYBLUE (-6625 2650);
FORCEPROP 2 LAST CDS_LIB pure_quanta
J 0
(-6500 2650);
DISPLAY INVISIBLE (-6500 2650);
FORCEPROP 1 LAST PATH I2085
J 0
(-6550 2800);
DISPLAY 0.978723 (-6550 2800);
PAINT WHITE (-6550 2800);
DISPLAY INVISIBLE (-6550 2800);
FORCEPROP 2 LAST BOM_COST MEM
J 2
(-6475 2800);
DISPLAY 0.744681 (-6475 2800);
PAINT WHITE (-6475 2800);
DISPLAY INVISIBLE (-6475 2800);
FORCEPROP 1 LAST WATTAGE 1/16W
J 2
(-6575 2575);
DISPLAY 0.489362 (-6575 2575);
PAINT SKYBLUE (-6575 2575);
DISPLAY INVISIBLE (-6575 2575);
FORCEPROP 1 LAST MATERIAL CHIP
J 2
(-6325 2625);
DISPLAY 0.489362 (-6325 2625);
PAINT SKYBLUE (-6325 2625);
DISPLAY INVISIBLE (-6325 2625);
FORCEPROP 1 LAST TOLERANCE 5%
J 0
(-6625 2625);
DISPLAY 0.489362 (-6625 2625);
PAINT SKYBLUE (-6625 2625);
DISPLAY INVISIBLE (-6625 2625);
FORCEPROP 1 LAST PART_NUMBER CS03302JB29
J 2
(-6400 2700);
DISPLAY 0.489362 (-6400 2700);
PAINT SKYBLUE (-6400 2700);
DISPLAY INVISIBLE (-6400 2700);
FORCEPROP 1 LAST PACK_TYPE 0402LF
J 2
(-6325 2575);
DISPLAY 0.489362 (-6325 2575);
PAINT SKYBLUE (-6325 2575);
DISPLAY INVISIBLE (-6325 2575);
FORCEPROP 2 LAST ROOM RST_CPU0_PLD_TO_DIMM
J 2
(-6475 2750);
DISPLAY 0.744681 (-6475 2750);
PAINT RED (-6475 2750);
DISPLAY INVISIBLE (-6475 2750);
FORCEADD Q_RES..1
(-6500 2700);
FORCEPROP 1 LAST LOCATION R228
J 0
(-6375 2700);
DISPLAY 0.489362 (-6375 2700);
PAINT SKYBLUE (-6375 2700);
FORCEPROP 0 LAST $SEC 1
J 0
(-6375 2750);
DISPLAY 0.680851 (-6375 2750);
PAINT MONO (-6375 2750);
DISPLAY INVISIBLE (-6375 2750);
FORCEPROP 0 LAST CDS_SEC 1
J 0
(-6375 2750);
DISPLAY 1.021277 (-6375 2750);
DISPLAY INVISIBLE (-6375 2750);
FORCEPROP 1 LASTPIN (-6600 2700) $PN 1
J 0
(-6588 2712);
DISPLAY 0.489362 (-6588 2712);
PAINT MONO (-6588 2712);
FORCEPROP 1 LASTPIN (-6400 2700) $PN 2
J 0
(-6438 2712);
DISPLAY 0.489362 (-6438 2712);
PAINT MONO (-6438 2712);
FORCEPROP 1 LAST VALUE 0
J 2
(-6625 2700);
DISPLAY 0.489362 (-6625 2700);
PAINT SKYBLUE (-6625 2700);
FORCEPROP 2 LAST ROOM RST_CPU0_PLD_TO_DIMM
J 2
(-6475 2800);
DISPLAY 0.744681 (-6475 2800);
PAINT RED (-6475 2800);
DISPLAY INVISIBLE (-6475 2800);
FORCEPROP 1 LAST PACK_TYPE 0402LF
J 2
(-6325 2625);
DISPLAY 0.489362 (-6325 2625);
PAINT SKYBLUE (-6325 2625);
DISPLAY INVISIBLE (-6325 2625);
FORCEPROP 1 LAST PART_NUMBER CS00002JB38
J 2
(-6400 2750);
DISPLAY 0.489362 (-6400 2750);
PAINT SKYBLUE (-6400 2750);
DISPLAY INVISIBLE (-6400 2750);
FORCEPROP 1 LAST TOLERANCE 5%
J 0
(-6625 2675);
DISPLAY 0.489362 (-6625 2675);
PAINT SKYBLUE (-6625 2675);
DISPLAY INVISIBLE (-6625 2675);
FORCEPROP 1 LAST MATERIAL CHIP
J 2
(-6325 2675);
DISPLAY 0.489362 (-6325 2675);
PAINT SKYBLUE (-6325 2675);
DISPLAY INVISIBLE (-6325 2675);
FORCEPROP 1 LAST WATTAGE 1/16W
J 2
(-6575 2625);
DISPLAY 0.489362 (-6575 2625);
PAINT SKYBLUE (-6575 2625);
DISPLAY INVISIBLE (-6575 2625);
FORCEPROP 1 LAST PATH I2086
J 0
(-6550 2850);
DISPLAY 0.978723 (-6550 2850);
PAINT WHITE (-6550 2850);
DISPLAY INVISIBLE (-6550 2850);
FORCEPROP 2 LAST CDS_LIB pure_quanta
J 2
(-6500 2700);
DISPLAY INVISIBLE (-6500 2700);
FORCEPROP 2 LAST BOM_COST MEM
J 2
(-6475 2850);
DISPLAY 0.744681 (-6475 2850);
PAINT WHITE (-6475 2850);
DISPLAY INVISIBLE (-6475 2850);
FORCEADD OFFPAGE..1
(-7475 3000);
FORCEPROP 2 LAST $XR1 114 
J 0
(-7846 3000);
DISPLAY 0.638298 (-7846 3000);
PAINT MONO (-7846 3000);
FORCEPROP 2 LAST $XR0 82 
J 0
(-7726 3000);
DISPLAY 0.638298 (-7726 3000);
PAINT MONO (-7726 3000);
FORCEPROP 1 LAST COMMENT_BODY TRUE
J 0
(-7350 2900);
DISPLAY 0.872340 (-7350 2900);
PAINT GREEN (-7350 2900);
DISPLAY INVISIBLE (-7350 2900);
FORCEPROP 1 LAST OFFPAGE TRUE
J 0
(-7150 2875);
DISPLAY 0.872340 (-7150 2875);
PAINT GREEN (-7150 2875);
DISPLAY INVISIBLE (-7150 2875);
FORCEPROP 2 LAST CDS_LIB standard
J 0
(-7475 3000);
DISPLAY INVISIBLE (-7475 3000);
FORCEPROP 2 LAST PATH I2087
J 0
(-7425 3075);
DISPLAY 0.680851 (-7425 3075);
DISPLAY INVISIBLE (-7425 3075);
FORCEADD OFFPAGE..1
(-7475 2950);
FORCEPROP 2 LAST $XR1 115 
J 0
(-7846 2950);
DISPLAY 0.638298 (-7846 2950);
PAINT MONO (-7846 2950);
FORCEPROP 2 LAST $XR0 82 
J 0
(-7726 2950);
DISPLAY 0.638298 (-7726 2950);
PAINT MONO (-7726 2950);
FORCEPROP 1 LAST OFFPAGE TRUE
J 0
(-7150 2825);
DISPLAY 0.872340 (-7150 2825);
PAINT GREEN (-7150 2825);
DISPLAY INVISIBLE (-7150 2825);
FORCEPROP 1 LAST COMMENT_BODY TRUE
J 0
(-7350 2850);
DISPLAY 0.872340 (-7350 2850);
PAINT GREEN (-7350 2850);
DISPLAY INVISIBLE (-7350 2850);
FORCEPROP 2 LAST CDS_LIB standard
J 0
(-7475 2950);
DISPLAY INVISIBLE (-7475 2950);
FORCEPROP 2 LAST PATH I2088
J 0
(-7425 3025);
DISPLAY 0.680851 (-7425 3025);
DISPLAY INVISIBLE (-7425 3025);
FORCEADD OFFPAGE..5
(-7475 2900);
FORCEPROP 2 LAST $XR0 176 
J 0
(-7730 2900);
DISPLAY 0.638298 (-7730 2900);
PAINT MONO (-7730 2900);
FORCEPROP 2 LAST CDS_LIB standard
J 0
(-7475 2900);
DISPLAY INVISIBLE (-7475 2900);
FORCEPROP 1 LAST OFFPAGE TRUE
J 0
(-7150 2775);
DISPLAY 0.872340 (-7150 2775);
PAINT GREEN (-7150 2775);
DISPLAY INVISIBLE (-7150 2775);
FORCEPROP 1 LAST COMMENT_BODY TRUE
J 0
(-7375 2825);
DISPLAY 0.872340 (-7375 2825);
PAINT GREEN (-7375 2825);
DISPLAY INVISIBLE (-7375 2825);
FORCEPROP 2 LAST PATH I2089
J 0
(-7425 2975);
DISPLAY 0.680851 (-7425 2975);
DISPLAY INVISIBLE (-7425 2975);
FORCEADD OFFPAGE..1
(-7475 2850);
FORCEPROP 2 LAST $XR0 176 
J 0
(-7757 2850);
DISPLAY 0.638298 (-7757 2850);
PAINT MONO (-7757 2850);
FORCEPROP 2 LAST CDS_LIB standard
J 0
(-7475 2850);
DISPLAY INVISIBLE (-7475 2850);
FORCEPROP 1 LAST OFFPAGE TRUE
J 0
(-7150 2725);
DISPLAY 0.872340 (-7150 2725);
PAINT GREEN (-7150 2725);
DISPLAY INVISIBLE (-7150 2725);
FORCEPROP 1 LAST COMMENT_BODY TRUE
J 0
(-7350 2750);
DISPLAY 0.872340 (-7350 2750);
PAINT GREEN (-7350 2750);
DISPLAY INVISIBLE (-7350 2750);
FORCEPROP 2 LAST PATH I2091
J 0
(-7425 2925);
DISPLAY 0.680851 (-7425 2925);
DISPLAY INVISIBLE (-7425 2925);
FORCEADD OFFPAGE..1
(-7475 2700);
FORCEPROP 2 LAST $XR1 111 
J 0
(-7877 2700);
DISPLAY 0.638298 (-7877 2700);
PAINT MONO (-7877 2700);
FORCEPROP 2 LAST $XR0 183 
J 0
(-7757 2700);
DISPLAY 0.638298 (-7757 2700);
PAINT MONO (-7757 2700);
FORCEPROP 2 LAST CDS_LIB standard
J 0
(-7475 2700);
DISPLAY INVISIBLE (-7475 2700);
FORCEPROP 1 LAST COMMENT_BODY TRUE
J 0
(-7350 2600);
DISPLAY 0.872340 (-7350 2600);
PAINT GREEN (-7350 2600);
DISPLAY INVISIBLE (-7350 2600);
FORCEPROP 1 LAST OFFPAGE TRUE
J 0
(-7150 2575);
DISPLAY 0.872340 (-7150 2575);
PAINT GREEN (-7150 2575);
DISPLAY INVISIBLE (-7150 2575);
FORCEPROP 2 LAST PATH I2093
J 0
(-7425 2775);
DISPLAY 0.680851 (-7425 2775);
DISPLAY INVISIBLE (-7425 2775);
FORCEADD OFFPAGE..5
(-7475 2650);
FORCEPROP 2 LAST $XR0 186 
J 0
(-7730 2650);
DISPLAY 0.638298 (-7730 2650);
PAINT MONO (-7730 2650);
FORCEPROP 2 LAST CDS_LIB standard
J 0
(-7475 2650);
DISPLAY INVISIBLE (-7475 2650);
FORCEPROP 2 LAST PATH I2094
J 0
(-7425 2725);
DISPLAY 0.680851 (-7425 2725);
DISPLAY INVISIBLE (-7425 2725);
FORCEPROP 1 LAST COMMENT_BODY TRUE
J 0
(-7375 2575);
DISPLAY 0.872340 (-7375 2575);
PAINT GREEN (-7375 2575);
DISPLAY INVISIBLE (-7375 2575);
FORCEPROP 1 LAST OFFPAGE TRUE
J 0
(-7150 2525);
DISPLAY 0.872340 (-7150 2525);
PAINT GREEN (-7150 2525);
DISPLAY INVISIBLE (-7150 2525);
FORCEADD Q_RES..1
(-6500 2450);
FORCEPROP 1 LAST LOCATION R286
J 0
(-6375 2450);
DISPLAY 0.489362 (-6375 2450);
PAINT SKYBLUE (-6375 2450);
FORCEPROP 0 LAST $SEC 1
J 0
(-6375 2500);
DISPLAY 0.680851 (-6375 2500);
PAINT MONO (-6375 2500);
DISPLAY INVISIBLE (-6375 2500);
FORCEPROP 0 LAST CDS_SEC 1
J 0
(-6375 2500);
DISPLAY 1.021277 (-6375 2500);
DISPLAY INVISIBLE (-6375 2500);
FORCEPROP 1 LASTPIN (-6600 2450) $PN 1
J 0
(-6588 2462);
DISPLAY 0.489362 (-6588 2462);
PAINT MONO (-6588 2462);
FORCEPROP 1 LASTPIN (-6400 2450) $PN 2
J 0
(-6438 2462);
DISPLAY 0.489362 (-6438 2462);
PAINT MONO (-6438 2462);
FORCEPROP 1 LAST VALUE 0
J 2
(-6625 2450);
DISPLAY 0.489362 (-6625 2450);
PAINT SKYBLUE (-6625 2450);
FORCEPROP 2 LAST ROOM RST_CPU0_PLD_TO_DIMM
J 2
(-6475 2550);
DISPLAY 0.744681 (-6475 2550);
PAINT RED (-6475 2550);
DISPLAY INVISIBLE (-6475 2550);
FORCEPROP 1 LAST PACK_TYPE 0402LF
J 2
(-6325 2375);
DISPLAY 0.489362 (-6325 2375);
PAINT SKYBLUE (-6325 2375);
DISPLAY INVISIBLE (-6325 2375);
FORCEPROP 1 LAST PART_NUMBER CS00002JB38
J 2
(-6400 2500);
DISPLAY 0.489362 (-6400 2500);
PAINT SKYBLUE (-6400 2500);
DISPLAY INVISIBLE (-6400 2500);
FORCEPROP 1 LAST TOLERANCE 5%
J 0
(-6625 2425);
DISPLAY 0.489362 (-6625 2425);
PAINT SKYBLUE (-6625 2425);
DISPLAY INVISIBLE (-6625 2425);
FORCEPROP 1 LAST MATERIAL CHIP
J 2
(-6325 2425);
DISPLAY 0.489362 (-6325 2425);
PAINT SKYBLUE (-6325 2425);
DISPLAY INVISIBLE (-6325 2425);
FORCEPROP 1 LAST WATTAGE 1/16W
J 2
(-6575 2375);
DISPLAY 0.489362 (-6575 2375);
PAINT SKYBLUE (-6575 2375);
DISPLAY INVISIBLE (-6575 2375);
FORCEPROP 1 LAST PATH I2095
J 0
(-6550 2600);
DISPLAY 0.978723 (-6550 2600);
PAINT WHITE (-6550 2600);
DISPLAY INVISIBLE (-6550 2600);
FORCEPROP 2 LAST CDS_LIB pure_quanta
J 2
(-6500 2450);
DISPLAY INVISIBLE (-6500 2450);
FORCEPROP 2 LAST BOM_COST MEM
J 2
(-6475 2600);
DISPLAY 0.744681 (-6475 2600);
PAINT WHITE (-6475 2600);
DISPLAY INVISIBLE (-6475 2600);
FORCEADD Q_RES..1
(-6500 2300);
FORCEPROP 1 LAST LOCATION R209
J 0
(-6375 2300);
DISPLAY 0.489362 (-6375 2300);
PAINT SKYBLUE (-6375 2300);
FORCEPROP 0 LAST $SEC 1
J 0
(-6375 2350);
DISPLAY 0.680851 (-6375 2350);
PAINT MONO (-6375 2350);
DISPLAY INVISIBLE (-6375 2350);
FORCEPROP 0 LAST CDS_SEC 1
J 0
(-6375 2350);
DISPLAY 1.021277 (-6375 2350);
DISPLAY INVISIBLE (-6375 2350);
FORCEPROP 1 LASTPIN (-6600 2300) $PN 1
J 0
(-6588 2312);
DISPLAY 0.489362 (-6588 2312);
PAINT MONO (-6588 2312);
FORCEPROP 1 LASTPIN (-6400 2300) $PN 2
J 0
(-6438 2312);
DISPLAY 0.489362 (-6438 2312);
PAINT MONO (-6438 2312);
FORCEPROP 1 LAST VALUE 0
J 2
(-6625 2300);
DISPLAY 0.489362 (-6625 2300);
PAINT SKYBLUE (-6625 2300);
FORCEPROP 2 LAST ROOM RST_CPU0_PLD_TO_DIMM
J 2
(-6475 2400);
DISPLAY 0.744681 (-6475 2400);
PAINT RED (-6475 2400);
DISPLAY INVISIBLE (-6475 2400);
FORCEPROP 1 LAST PACK_TYPE 0402LF
J 2
(-6325 2225);
DISPLAY 0.489362 (-6325 2225);
PAINT SKYBLUE (-6325 2225);
DISPLAY INVISIBLE (-6325 2225);
FORCEPROP 1 LAST PART_NUMBER CS00002JB38
J 2
(-6400 2350);
DISPLAY 0.489362 (-6400 2350);
PAINT SKYBLUE (-6400 2350);
DISPLAY INVISIBLE (-6400 2350);
FORCEPROP 1 LAST TOLERANCE 5%
J 0
(-6625 2275);
DISPLAY 0.489362 (-6625 2275);
PAINT SKYBLUE (-6625 2275);
DISPLAY INVISIBLE (-6625 2275);
FORCEPROP 1 LAST MATERIAL CHIP
J 2
(-6325 2275);
DISPLAY 0.489362 (-6325 2275);
PAINT SKYBLUE (-6325 2275);
DISPLAY INVISIBLE (-6325 2275);
FORCEPROP 1 LAST WATTAGE 1/16W
J 2
(-6575 2225);
DISPLAY 0.489362 (-6575 2225);
PAINT SKYBLUE (-6575 2225);
DISPLAY INVISIBLE (-6575 2225);
FORCEPROP 1 LAST PATH I2096
J 0
(-6550 2450);
DISPLAY 0.978723 (-6550 2450);
PAINT WHITE (-6550 2450);
DISPLAY INVISIBLE (-6550 2450);
FORCEPROP 2 LAST CDS_LIB pure_quanta
J 0
(-6500 2300);
DISPLAY INVISIBLE (-6500 2300);
FORCEPROP 2 LAST BOM_COST MEM
J 2
(-6475 2450);
DISPLAY 0.744681 (-6475 2450);
PAINT WHITE (-6475 2450);
DISPLAY INVISIBLE (-6475 2450);
FORCEADD Q_RES..1
(-6500 2000);
FORCEPROP 1 LAST LOCATION R279
J 0
(-6375 2000);
DISPLAY 0.489362 (-6375 2000);
PAINT SKYBLUE (-6375 2000);
FORCEPROP 0 LAST $SEC 1
J 2
(-6375 2050);
DISPLAY 0.680851 (-6375 2050);
PAINT MONO (-6375 2050);
DISPLAY INVISIBLE (-6375 2050);
FORCEPROP 0 LAST CDS_SEC 1
J 2
(-6375 2050);
DISPLAY 1.021277 (-6375 2050);
DISPLAY INVISIBLE (-6375 2050);
FORCEPROP 1 LASTPIN (-6600 2000) $PN 1
J 0
(-6588 2012);
DISPLAY 0.489362 (-6588 2012);
PAINT MONO (-6588 2012);
FORCEPROP 1 LASTPIN (-6400 2000) $PN 2
J 0
(-6438 2012);
DISPLAY 0.489362 (-6438 2012);
PAINT MONO (-6438 2012);
FORCEPROP 1 LAST VALUE 33
J 2
(-6625 2000);
DISPLAY 0.489362 (-6625 2000);
PAINT SKYBLUE (-6625 2000);
FORCEPROP 2 LAST ROOM RST_CPU0_PLD_TO_DIMM
J 2
(-6475 2100);
DISPLAY 0.744681 (-6475 2100);
PAINT RED (-6475 2100);
DISPLAY INVISIBLE (-6475 2100);
FORCEPROP 1 LAST PACK_TYPE 0402LF
J 2
(-6325 1925);
DISPLAY 0.489362 (-6325 1925);
PAINT SKYBLUE (-6325 1925);
DISPLAY INVISIBLE (-6325 1925);
FORCEPROP 1 LAST PART_NUMBER CS03302JB29
J 2
(-6400 2050);
DISPLAY 0.489362 (-6400 2050);
PAINT SKYBLUE (-6400 2050);
DISPLAY INVISIBLE (-6400 2050);
FORCEPROP 1 LAST TOLERANCE 5%
J 0
(-6625 1975);
DISPLAY 0.489362 (-6625 1975);
PAINT SKYBLUE (-6625 1975);
DISPLAY INVISIBLE (-6625 1975);
FORCEPROP 1 LAST MATERIAL CHIP
J 2
(-6325 1975);
DISPLAY 0.489362 (-6325 1975);
PAINT SKYBLUE (-6325 1975);
DISPLAY INVISIBLE (-6325 1975);
FORCEPROP 1 LAST WATTAGE 1/16W
J 2
(-6575 1925);
DISPLAY 0.489362 (-6575 1925);
PAINT SKYBLUE (-6575 1925);
DISPLAY INVISIBLE (-6575 1925);
FORCEPROP 1 LAST PATH I2097
J 0
(-6550 2150);
DISPLAY 0.978723 (-6550 2150);
PAINT WHITE (-6550 2150);
DISPLAY INVISIBLE (-6550 2150);
FORCEPROP 2 LAST BOM_COST MEM
J 2
(-6475 2150);
DISPLAY 0.744681 (-6475 2150);
PAINT WHITE (-6475 2150);
DISPLAY INVISIBLE (-6475 2150);
FORCEPROP 2 LAST CDS_LIB pure_quanta
J 2
(-6500 2000);
DISPLAY INVISIBLE (-6500 2000);
FORCEADD Q_RES..1
(-6500 1950);
FORCEPROP 1 LAST LOCATION R280
J 0
(-6375 1950);
DISPLAY 0.489362 (-6375 1950);
PAINT SKYBLUE (-6375 1950);
FORCEPROP 0 LAST $SEC 1
J 0
(-6375 2000);
DISPLAY 0.680851 (-6375 2000);
PAINT MONO (-6375 2000);
DISPLAY INVISIBLE (-6375 2000);
FORCEPROP 0 LAST CDS_SEC 1
J 0
(-6375 2000);
DISPLAY 1.021277 (-6375 2000);
DISPLAY INVISIBLE (-6375 2000);
FORCEPROP 1 LASTPIN (-6600 1950) $PN 1
J 0
(-6588 1962);
DISPLAY 0.489362 (-6588 1962);
PAINT MONO (-6588 1962);
FORCEPROP 1 LASTPIN (-6400 1950) $PN 2
J 0
(-6438 1962);
DISPLAY 0.489362 (-6438 1962);
PAINT MONO (-6438 1962);
FORCEPROP 1 LAST VALUE 0
J 2
(-6625 1950);
DISPLAY 0.489362 (-6625 1950);
PAINT SKYBLUE (-6625 1950);
FORCEPROP 2 LAST ROOM RST_CPU0_PLD_TO_DIMM
J 2
(-6475 2050);
DISPLAY 0.744681 (-6475 2050);
PAINT RED (-6475 2050);
DISPLAY INVISIBLE (-6475 2050);
FORCEPROP 1 LAST PACK_TYPE 0402LF
J 2
(-6325 1875);
DISPLAY 0.489362 (-6325 1875);
PAINT SKYBLUE (-6325 1875);
DISPLAY INVISIBLE (-6325 1875);
FORCEPROP 1 LAST PART_NUMBER CS00002JB38
J 2
(-6400 2000);
DISPLAY 0.489362 (-6400 2000);
PAINT SKYBLUE (-6400 2000);
DISPLAY INVISIBLE (-6400 2000);
FORCEPROP 1 LAST TOLERANCE 5%
J 0
(-6625 1925);
DISPLAY 0.489362 (-6625 1925);
PAINT SKYBLUE (-6625 1925);
DISPLAY INVISIBLE (-6625 1925);
FORCEPROP 1 LAST MATERIAL CHIP
J 2
(-6325 1925);
DISPLAY 0.489362 (-6325 1925);
PAINT SKYBLUE (-6325 1925);
DISPLAY INVISIBLE (-6325 1925);
FORCEPROP 1 LAST WATTAGE 1/16W
J 2
(-6575 1875);
DISPLAY 0.489362 (-6575 1875);
PAINT SKYBLUE (-6575 1875);
DISPLAY INVISIBLE (-6575 1875);
FORCEPROP 1 LAST PATH I2098
J 0
(-6550 2100);
DISPLAY 0.978723 (-6550 2100);
PAINT WHITE (-6550 2100);
DISPLAY INVISIBLE (-6550 2100);
FORCEPROP 2 LAST BOM_COST MEM
J 2
(-6475 2100);
DISPLAY 0.744681 (-6475 2100);
PAINT WHITE (-6475 2100);
DISPLAY INVISIBLE (-6475 2100);
FORCEPROP 2 LAST CDS_LIB pure_quanta
J 2
(-6500 1950);
DISPLAY INVISIBLE (-6500 1950);
FORCEADD Q_RES..1
(-6500 1900);
FORCEPROP 1 LAST LOCATION R289
J 0
(-6375 1900);
DISPLAY 0.489362 (-6375 1900);
PAINT SKYBLUE (-6375 1900);
FORCEPROP 0 LAST $SEC 1
J 2
(-6375 1950);
DISPLAY 0.680851 (-6375 1950);
PAINT MONO (-6375 1950);
DISPLAY INVISIBLE (-6375 1950);
FORCEPROP 0 LAST CDS_SEC 1
J 2
(-6375 1950);
DISPLAY 1.021277 (-6375 1950);
DISPLAY INVISIBLE (-6375 1950);
FORCEPROP 1 LASTPIN (-6600 1900) $PN 1
J 0
(-6588 1912);
DISPLAY 0.489362 (-6588 1912);
PAINT MONO (-6588 1912);
FORCEPROP 1 LASTPIN (-6400 1900) $PN 2
J 0
(-6438 1912);
DISPLAY 0.489362 (-6438 1912);
PAINT MONO (-6438 1912);
FORCEPROP 1 LAST VALUE 33
J 2
(-6625 1900);
DISPLAY 0.489362 (-6625 1900);
PAINT SKYBLUE (-6625 1900);
FORCEPROP 2 LAST ROOM RST_CPU0_PLD_TO_DIMM
J 2
(-6475 2000);
DISPLAY 0.744681 (-6475 2000);
PAINT RED (-6475 2000);
DISPLAY INVISIBLE (-6475 2000);
FORCEPROP 1 LAST PACK_TYPE 0402LF
J 2
(-6325 1825);
DISPLAY 0.489362 (-6325 1825);
PAINT SKYBLUE (-6325 1825);
DISPLAY INVISIBLE (-6325 1825);
FORCEPROP 1 LAST PART_NUMBER CS03302JB29
J 2
(-6400 1950);
DISPLAY 0.489362 (-6400 1950);
PAINT SKYBLUE (-6400 1950);
DISPLAY INVISIBLE (-6400 1950);
FORCEPROP 1 LAST TOLERANCE 5%
J 0
(-6625 1875);
DISPLAY 0.489362 (-6625 1875);
PAINT SKYBLUE (-6625 1875);
DISPLAY INVISIBLE (-6625 1875);
FORCEPROP 1 LAST MATERIAL CHIP
J 2
(-6325 1875);
DISPLAY 0.489362 (-6325 1875);
PAINT SKYBLUE (-6325 1875);
DISPLAY INVISIBLE (-6325 1875);
FORCEPROP 1 LAST WATTAGE 1/16W
J 2
(-6575 1825);
DISPLAY 0.489362 (-6575 1825);
PAINT SKYBLUE (-6575 1825);
DISPLAY INVISIBLE (-6575 1825);
FORCEPROP 1 LAST PATH I2099
J 0
(-6550 2050);
DISPLAY 0.978723 (-6550 2050);
PAINT WHITE (-6550 2050);
DISPLAY INVISIBLE (-6550 2050);
FORCEPROP 2 LAST BOM_COST MEM
J 2
(-6475 2050);
DISPLAY 0.744681 (-6475 2050);
PAINT WHITE (-6475 2050);
DISPLAY INVISIBLE (-6475 2050);
FORCEPROP 2 LAST CDS_LIB pure_quanta
J 2
(-6500 1900);
DISPLAY INVISIBLE (-6500 1900);
FORCEADD Q_RES..1
(-6500 1600);
FORCEPROP 1 LAST LOCATION R176
J 0
(-6375 1600);
DISPLAY 0.489362 (-6375 1600);
PAINT SKYBLUE (-6375 1600);
FORCEPROP 0 LAST $SEC 1
J 2
(-6375 1650);
DISPLAY 0.680851 (-6375 1650);
PAINT MONO (-6375 1650);
DISPLAY INVISIBLE (-6375 1650);
FORCEPROP 0 LAST CDS_SEC 1
J 2
(-6375 1650);
DISPLAY 1.021277 (-6375 1650);
DISPLAY INVISIBLE (-6375 1650);
FORCEPROP 1 LASTPIN (-6600 1600) $PN 1
J 0
(-6588 1612);
DISPLAY 0.489362 (-6588 1612);
PAINT MONO (-6588 1612);
FORCEPROP 1 LASTPIN (-6400 1600) $PN 2
J 0
(-6438 1612);
DISPLAY 0.489362 (-6438 1612);
PAINT MONO (-6438 1612);
FORCEPROP 1 LAST VALUE 33
J 2
(-6625 1600);
DISPLAY 0.489362 (-6625 1600);
PAINT SKYBLUE (-6625 1600);
FORCEPROP 2 LAST ROOM RST_CPU0_PLD_TO_DIMM
J 2
(-6475 1700);
DISPLAY 0.744681 (-6475 1700);
PAINT RED (-6475 1700);
DISPLAY INVISIBLE (-6475 1700);
FORCEPROP 1 LAST PACK_TYPE 0402LF
J 2
(-6325 1525);
DISPLAY 0.489362 (-6325 1525);
PAINT SKYBLUE (-6325 1525);
DISPLAY INVISIBLE (-6325 1525);
FORCEPROP 1 LAST PART_NUMBER CS03302JB29
J 2
(-6400 1650);
DISPLAY 0.489362 (-6400 1650);
PAINT SKYBLUE (-6400 1650);
DISPLAY INVISIBLE (-6400 1650);
FORCEPROP 1 LAST TOLERANCE 5%
J 0
(-6625 1575);
DISPLAY 0.489362 (-6625 1575);
PAINT SKYBLUE (-6625 1575);
DISPLAY INVISIBLE (-6625 1575);
FORCEPROP 1 LAST MATERIAL CHIP
J 2
(-6325 1575);
DISPLAY 0.489362 (-6325 1575);
PAINT SKYBLUE (-6325 1575);
DISPLAY INVISIBLE (-6325 1575);
FORCEPROP 1 LAST WATTAGE 1/16W
J 2
(-6575 1525);
DISPLAY 0.489362 (-6575 1525);
PAINT SKYBLUE (-6575 1525);
DISPLAY INVISIBLE (-6575 1525);
FORCEPROP 1 LAST PATH I2100
J 0
(-6550 1750);
DISPLAY 0.978723 (-6550 1750);
PAINT WHITE (-6550 1750);
DISPLAY INVISIBLE (-6550 1750);
FORCEPROP 2 LAST CDS_LIB pure_quanta
J 2
(-6500 1600);
DISPLAY INVISIBLE (-6500 1600);
FORCEPROP 2 LAST BOM_COST MEM
J 2
(-6475 1750);
DISPLAY 0.744681 (-6475 1750);
PAINT WHITE (-6475 1750);
DISPLAY INVISIBLE (-6475 1750);
FORCEADD Q_RES..1
(-6500 1700);
FORCEPROP 1 LAST LOCATION R224
J 0
(-6375 1700);
DISPLAY 0.489362 (-6375 1700);
PAINT SKYBLUE (-6375 1700);
FORCEPROP 0 LAST $SEC 1
J 2
(-6375 1750);
DISPLAY 0.680851 (-6375 1750);
PAINT MONO (-6375 1750);
DISPLAY INVISIBLE (-6375 1750);
FORCEPROP 0 LAST CDS_SEC 1
J 2
(-6375 1750);
DISPLAY 1.021277 (-6375 1750);
DISPLAY INVISIBLE (-6375 1750);
FORCEPROP 1 LASTPIN (-6600 1700) $PN 1
J 0
(-6588 1712);
DISPLAY 0.489362 (-6588 1712);
PAINT MONO (-6588 1712);
FORCEPROP 1 LASTPIN (-6400 1700) $PN 2
J 0
(-6438 1712);
DISPLAY 0.489362 (-6438 1712);
PAINT MONO (-6438 1712);
FORCEPROP 1 LAST VALUE 33
J 2
(-6625 1700);
DISPLAY 0.489362 (-6625 1700);
PAINT SKYBLUE (-6625 1700);
FORCEPROP 2 LAST ROOM RST_CPU0_PLD_TO_DIMM
J 2
(-6475 1800);
DISPLAY 0.744681 (-6475 1800);
PAINT RED (-6475 1800);
DISPLAY INVISIBLE (-6475 1800);
FORCEPROP 1 LAST PACK_TYPE 0402LF
J 2
(-6325 1625);
DISPLAY 0.489362 (-6325 1625);
PAINT SKYBLUE (-6325 1625);
DISPLAY INVISIBLE (-6325 1625);
FORCEPROP 1 LAST PART_NUMBER CS03302JB29
J 2
(-6400 1750);
DISPLAY 0.489362 (-6400 1750);
PAINT SKYBLUE (-6400 1750);
DISPLAY INVISIBLE (-6400 1750);
FORCEPROP 1 LAST TOLERANCE 5%
J 0
(-6625 1675);
DISPLAY 0.489362 (-6625 1675);
PAINT SKYBLUE (-6625 1675);
DISPLAY INVISIBLE (-6625 1675);
FORCEPROP 1 LAST MATERIAL CHIP
J 2
(-6325 1675);
DISPLAY 0.489362 (-6325 1675);
PAINT SKYBLUE (-6325 1675);
DISPLAY INVISIBLE (-6325 1675);
FORCEPROP 1 LAST WATTAGE 1/16W
J 2
(-6575 1625);
DISPLAY 0.489362 (-6575 1625);
PAINT SKYBLUE (-6575 1625);
DISPLAY INVISIBLE (-6575 1625);
FORCEPROP 1 LAST PATH I2101
J 0
(-6550 1850);
DISPLAY 0.978723 (-6550 1850);
PAINT WHITE (-6550 1850);
DISPLAY INVISIBLE (-6550 1850);
FORCEPROP 2 LAST CDS_LIB pure_quanta
J 2
(-6500 1700);
DISPLAY INVISIBLE (-6500 1700);
FORCEPROP 2 LAST BOM_COST MEM
J 2
(-6475 1850);
DISPLAY 0.744681 (-6475 1850);
PAINT WHITE (-6475 1850);
DISPLAY INVISIBLE (-6475 1850);
FORCEADD Q_RES..1
(-6500 1350);
FORCEPROP 1 LAST LOCATION R283
J 0
(-6375 1350);
DISPLAY 0.489362 (-6375 1350);
PAINT SKYBLUE (-6375 1350);
FORCEPROP 0 LAST $SEC 1
J 0
(-6375 1400);
DISPLAY 0.680851 (-6375 1400);
PAINT MONO (-6375 1400);
DISPLAY INVISIBLE (-6375 1400);
FORCEPROP 0 LAST CDS_SEC 1
J 0
(-6375 1400);
DISPLAY 1.021277 (-6375 1400);
DISPLAY INVISIBLE (-6375 1400);
FORCEPROP 1 LASTPIN (-6600 1350) $PN 1
J 0
(-6588 1362);
DISPLAY 0.489362 (-6588 1362);
PAINT MONO (-6588 1362);
FORCEPROP 1 LASTPIN (-6400 1350) $PN 2
J 0
(-6438 1362);
DISPLAY 0.489362 (-6438 1362);
PAINT MONO (-6438 1362);
FORCEPROP 1 LAST VALUE 0
J 2
(-6625 1350);
DISPLAY 0.489362 (-6625 1350);
PAINT SKYBLUE (-6625 1350);
FORCEPROP 2 LAST ROOM RST_CPU0_PLD_TO_DIMM
J 2
(-6475 1450);
DISPLAY 0.744681 (-6475 1450);
PAINT RED (-6475 1450);
DISPLAY INVISIBLE (-6475 1450);
FORCEPROP 1 LAST PACK_TYPE 0402LF
J 2
(-6325 1275);
DISPLAY 0.489362 (-6325 1275);
PAINT SKYBLUE (-6325 1275);
DISPLAY INVISIBLE (-6325 1275);
FORCEPROP 1 LAST PART_NUMBER CS00002JB38
J 2
(-6400 1400);
DISPLAY 0.489362 (-6400 1400);
PAINT SKYBLUE (-6400 1400);
DISPLAY INVISIBLE (-6400 1400);
FORCEPROP 1 LAST TOLERANCE 5%
J 0
(-6625 1325);
DISPLAY 0.489362 (-6625 1325);
PAINT SKYBLUE (-6625 1325);
DISPLAY INVISIBLE (-6625 1325);
FORCEPROP 1 LAST MATERIAL CHIP
J 2
(-6325 1325);
DISPLAY 0.489362 (-6325 1325);
PAINT SKYBLUE (-6325 1325);
DISPLAY INVISIBLE (-6325 1325);
FORCEPROP 1 LAST WATTAGE 1/16W
J 2
(-6575 1275);
DISPLAY 0.489362 (-6575 1275);
PAINT SKYBLUE (-6575 1275);
DISPLAY INVISIBLE (-6575 1275);
FORCEPROP 1 LAST PATH I2102
J 0
(-6550 1500);
DISPLAY 0.978723 (-6550 1500);
PAINT WHITE (-6550 1500);
DISPLAY INVISIBLE (-6550 1500);
FORCEPROP 2 LAST BOM_COST MEM
J 2
(-6475 1500);
DISPLAY 0.744681 (-6475 1500);
PAINT WHITE (-6475 1500);
DISPLAY INVISIBLE (-6475 1500);
FORCEPROP 2 LAST CDS_LIB pure_quanta
J 2
(-6500 1350);
DISPLAY INVISIBLE (-6500 1350);
FORCEADD Q_RES..1
(-6500 1400);
FORCEPROP 1 LAST LOCATION R282
J 0
(-6375 1400);
DISPLAY 0.489362 (-6375 1400);
PAINT SKYBLUE (-6375 1400);
FORCEPROP 0 LAST $SEC 1
J 2
(-6375 1450);
DISPLAY 0.680851 (-6375 1450);
PAINT MONO (-6375 1450);
DISPLAY INVISIBLE (-6375 1450);
FORCEPROP 0 LAST CDS_SEC 1
J 2
(-6375 1450);
DISPLAY 1.021277 (-6375 1450);
DISPLAY INVISIBLE (-6375 1450);
FORCEPROP 1 LASTPIN (-6600 1400) $PN 1
J 0
(-6588 1412);
DISPLAY 0.489362 (-6588 1412);
PAINT MONO (-6588 1412);
FORCEPROP 1 LASTPIN (-6400 1400) $PN 2
J 0
(-6438 1412);
DISPLAY 0.489362 (-6438 1412);
PAINT MONO (-6438 1412);
FORCEPROP 1 LAST VALUE 33
J 2
(-6625 1400);
DISPLAY 0.489362 (-6625 1400);
PAINT SKYBLUE (-6625 1400);
FORCEPROP 2 LAST ROOM RST_CPU0_PLD_TO_DIMM
J 2
(-6475 1500);
DISPLAY 0.744681 (-6475 1500);
PAINT RED (-6475 1500);
DISPLAY INVISIBLE (-6475 1500);
FORCEPROP 1 LAST PACK_TYPE 0402LF
J 2
(-6325 1325);
DISPLAY 0.489362 (-6325 1325);
PAINT SKYBLUE (-6325 1325);
DISPLAY INVISIBLE (-6325 1325);
FORCEPROP 1 LAST PART_NUMBER CS03302JB29
J 2
(-6400 1450);
DISPLAY 0.489362 (-6400 1450);
PAINT SKYBLUE (-6400 1450);
DISPLAY INVISIBLE (-6400 1450);
FORCEPROP 1 LAST TOLERANCE 5%
J 0
(-6625 1375);
DISPLAY 0.489362 (-6625 1375);
PAINT SKYBLUE (-6625 1375);
DISPLAY INVISIBLE (-6625 1375);
FORCEPROP 1 LAST MATERIAL CHIP
J 2
(-6325 1375);
DISPLAY 0.489362 (-6325 1375);
PAINT SKYBLUE (-6325 1375);
DISPLAY INVISIBLE (-6325 1375);
FORCEPROP 1 LAST WATTAGE 1/16W
J 2
(-6575 1325);
DISPLAY 0.489362 (-6575 1325);
PAINT SKYBLUE (-6575 1325);
DISPLAY INVISIBLE (-6575 1325);
FORCEPROP 1 LAST PATH I2103
J 0
(-6550 1550);
DISPLAY 0.978723 (-6550 1550);
PAINT WHITE (-6550 1550);
DISPLAY INVISIBLE (-6550 1550);
FORCEPROP 2 LAST BOM_COST MEM
J 2
(-6475 1550);
DISPLAY 0.744681 (-6475 1550);
PAINT WHITE (-6475 1550);
DISPLAY INVISIBLE (-6475 1550);
FORCEPROP 2 LAST CDS_LIB pure_quanta
J 2
(-6500 1400);
DISPLAY INVISIBLE (-6500 1400);
FORCEADD Q_RES..1
(-6500 1450);
FORCEPROP 1 LAST LOCATION R218
J 0
(-6375 1450);
DISPLAY 0.489362 (-6375 1450);
PAINT SKYBLUE (-6375 1450);
FORCEPROP 0 LAST $SEC 1
J 2
(-6375 1500);
DISPLAY 0.680851 (-6375 1500);
PAINT MONO (-6375 1500);
DISPLAY INVISIBLE (-6375 1500);
FORCEPROP 0 LAST CDS_SEC 1
J 2
(-6375 1500);
DISPLAY 1.021277 (-6375 1500);
DISPLAY INVISIBLE (-6375 1500);
FORCEPROP 1 LASTPIN (-6600 1450) $PN 1
J 0
(-6588 1462);
DISPLAY 0.489362 (-6588 1462);
PAINT MONO (-6588 1462);
FORCEPROP 1 LASTPIN (-6400 1450) $PN 2
J 0
(-6438 1462);
DISPLAY 0.489362 (-6438 1462);
PAINT MONO (-6438 1462);
FORCEPROP 1 LAST VALUE 33
J 2
(-6625 1450);
DISPLAY 0.489362 (-6625 1450);
PAINT SKYBLUE (-6625 1450);
FORCEPROP 2 LAST ROOM RST_CPU0_PLD_TO_DIMM
J 2
(-6475 1550);
DISPLAY 0.744681 (-6475 1550);
PAINT RED (-6475 1550);
DISPLAY INVISIBLE (-6475 1550);
FORCEPROP 1 LAST PACK_TYPE 0402LF
J 2
(-6325 1375);
DISPLAY 0.489362 (-6325 1375);
PAINT SKYBLUE (-6325 1375);
DISPLAY INVISIBLE (-6325 1375);
FORCEPROP 1 LAST PART_NUMBER CS03302JB29
J 2
(-6400 1500);
DISPLAY 0.489362 (-6400 1500);
PAINT SKYBLUE (-6400 1500);
DISPLAY INVISIBLE (-6400 1500);
FORCEPROP 1 LAST TOLERANCE 5%
J 0
(-6625 1425);
DISPLAY 0.489362 (-6625 1425);
PAINT SKYBLUE (-6625 1425);
DISPLAY INVISIBLE (-6625 1425);
FORCEPROP 1 LAST MATERIAL CHIP
J 2
(-6325 1425);
DISPLAY 0.489362 (-6325 1425);
PAINT SKYBLUE (-6325 1425);
DISPLAY INVISIBLE (-6325 1425);
FORCEPROP 1 LAST WATTAGE 1/16W
J 2
(-6575 1375);
DISPLAY 0.489362 (-6575 1375);
PAINT SKYBLUE (-6575 1375);
DISPLAY INVISIBLE (-6575 1375);
FORCEPROP 1 LAST PATH I2104
J 0
(-6550 1600);
DISPLAY 0.978723 (-6550 1600);
PAINT WHITE (-6550 1600);
DISPLAY INVISIBLE (-6550 1600);
FORCEPROP 2 LAST BOM_COST MEM
J 2
(-6475 1600);
DISPLAY 0.744681 (-6475 1600);
PAINT WHITE (-6475 1600);
DISPLAY INVISIBLE (-6475 1600);
FORCEPROP 2 LAST CDS_LIB pure_quanta
J 2
(-6500 1450);
DISPLAY INVISIBLE (-6500 1450);
FORCEADD Q_RES..1
(-6500 1150);
FORCEPROP 1 LAST LOCATION R1282
J 0
(-6375 1150);
DISPLAY 0.489362 (-6375 1150);
PAINT SKYBLUE (-6375 1150);
FORCEPROP 0 LAST $SEC 1
J 0
(-6425 1200);
DISPLAY 0.680851 (-6425 1200);
PAINT MONO (-6425 1200);
DISPLAY INVISIBLE (-6425 1200);
FORCEPROP 0 LAST CDS_SEC 1
J 0
(-6425 1200);
DISPLAY 0.680851 (-6425 1200);
DISPLAY INVISIBLE (-6425 1200);
FORCEPROP 1 LASTPIN (-6600 1150) $PN 1
J 0
(-6588 1162);
DISPLAY 0.489362 (-6588 1162);
PAINT MONO (-6588 1162);
FORCEPROP 1 LASTPIN (-6400 1150) $PN 2
J 0
(-6438 1162);
DISPLAY 0.489362 (-6438 1162);
PAINT MONO (-6438 1162);
FORCEPROP 1 LAST VALUE 33
J 2
(-6625 1150);
DISPLAY 0.489362 (-6625 1150);
PAINT SKYBLUE (-6625 1150);
FORCEPROP 2 LAST ROOM RST_CPU0_PLD_TO_DIMM
J 2
(-6475 1250);
DISPLAY 0.744681 (-6475 1250);
PAINT RED (-6475 1250);
DISPLAY INVISIBLE (-6475 1250);
FORCEPROP 1 LAST PACK_TYPE 0402LF
J 2
(-6325 1075);
DISPLAY 0.489362 (-6325 1075);
PAINT SKYBLUE (-6325 1075);
DISPLAY INVISIBLE (-6325 1075);
FORCEPROP 1 LAST PART_NUMBER CS03302JB29
J 2
(-6400 1200);
DISPLAY 0.489362 (-6400 1200);
PAINT SKYBLUE (-6400 1200);
DISPLAY INVISIBLE (-6400 1200);
FORCEPROP 1 LAST TOLERANCE 5%
J 0
(-6625 1125);
DISPLAY 0.489362 (-6625 1125);
PAINT SKYBLUE (-6625 1125);
DISPLAY INVISIBLE (-6625 1125);
FORCEPROP 1 LAST MATERIAL CHIP
J 2
(-6325 1125);
DISPLAY 0.489362 (-6325 1125);
PAINT SKYBLUE (-6325 1125);
DISPLAY INVISIBLE (-6325 1125);
FORCEPROP 1 LAST WATTAGE 1/16W
J 2
(-6575 1075);
DISPLAY 0.489362 (-6575 1075);
PAINT SKYBLUE (-6575 1075);
DISPLAY INVISIBLE (-6575 1075);
FORCEPROP 1 LAST PATH I2106
J 0
(-6550 1300);
DISPLAY 0.978723 (-6550 1300);
PAINT WHITE (-6550 1300);
DISPLAY INVISIBLE (-6550 1300);
FORCEPROP 2 LAST CDS_LIB pure_quanta
J 0
(-6500 1150);
DISPLAY INVISIBLE (-6500 1150);
FORCEPROP 2 LAST BOM_COST MEM
J 2
(-6475 1300);
DISPLAY 0.744681 (-6475 1300);
PAINT WHITE (-6475 1300);
DISPLAY INVISIBLE (-6475 1300);
FORCEADD Q_RES..1
(-6500 750);
FORCEPROP 1 LAST LOCATION R199
J 0
(-6400 750);
DISPLAY 0.489362 (-6400 750);
PAINT SKYBLUE (-6400 750);
FORCEPROP 0 LAST $SEC 1
J 0
(-6400 800);
DISPLAY 0.680851 (-6400 800);
PAINT MONO (-6400 800);
DISPLAY INVISIBLE (-6400 800);
FORCEPROP 0 LAST CDS_SEC 1
J 0
(-6400 800);
DISPLAY 0.680851 (-6400 800);
DISPLAY INVISIBLE (-6400 800);
FORCEPROP 1 LASTPIN (-6600 750) $PN 1
J 0
(-6588 762);
DISPLAY 0.489362 (-6588 762);
PAINT MONO (-6588 762);
FORCEPROP 1 LASTPIN (-6400 750) $PN 2
J 0
(-6438 762);
DISPLAY 0.489362 (-6438 762);
PAINT MONO (-6438 762);
FORCEPROP 1 LAST VALUE 33
J 2
(-6625 750);
DISPLAY 0.489362 (-6625 750);
PAINT SKYBLUE (-6625 750);
FORCEPROP 2 LAST ROOM RST_CPU0_PLD_TO_DIMM
J 2
(-6475 850);
DISPLAY 0.744681 (-6475 850);
PAINT RED (-6475 850);
DISPLAY INVISIBLE (-6475 850);
FORCEPROP 1 LAST PACK_TYPE 0402LF
J 2
(-6325 675);
DISPLAY 0.489362 (-6325 675);
PAINT SKYBLUE (-6325 675);
DISPLAY INVISIBLE (-6325 675);
FORCEPROP 1 LAST PART_NUMBER CS03302JB29
J 2
(-6400 800);
DISPLAY 0.489362 (-6400 800);
PAINT SKYBLUE (-6400 800);
DISPLAY INVISIBLE (-6400 800);
FORCEPROP 1 LAST TOLERANCE 5%
J 0
(-6625 725);
DISPLAY 0.489362 (-6625 725);
PAINT SKYBLUE (-6625 725);
DISPLAY INVISIBLE (-6625 725);
FORCEPROP 1 LAST MATERIAL CHIP
J 2
(-6325 725);
DISPLAY 0.489362 (-6325 725);
PAINT SKYBLUE (-6325 725);
DISPLAY INVISIBLE (-6325 725);
FORCEPROP 1 LAST WATTAGE 1/16W
J 2
(-6575 675);
DISPLAY 0.489362 (-6575 675);
PAINT SKYBLUE (-6575 675);
DISPLAY INVISIBLE (-6575 675);
FORCEPROP 1 LAST PATH I2107
J 0
(-6550 900);
DISPLAY 0.978723 (-6550 900);
PAINT WHITE (-6550 900);
DISPLAY INVISIBLE (-6550 900);
FORCEPROP 2 LAST CDS_LIB pure_quanta
J 0
(-6500 750);
DISPLAY INVISIBLE (-6500 750);
FORCEPROP 2 LAST BOM_COST MEM
J 2
(-6475 900);
DISPLAY 0.744681 (-6475 900);
PAINT WHITE (-6475 900);
DISPLAY INVISIBLE (-6475 900);
FORCEADD Q_RES..1
(-6500 850);
FORCEPROP 1 LAST LOCATION R1063
J 0
(-6400 850);
DISPLAY 0.489362 (-6400 850);
PAINT SKYBLUE (-6400 850);
FORCEPROP 0 LAST $SEC 1
J 0
(-6400 900);
DISPLAY 0.680851 (-6400 900);
PAINT MONO (-6400 900);
DISPLAY INVISIBLE (-6400 900);
FORCEPROP 0 LAST CDS_SEC 1
J 0
(-6400 900);
DISPLAY 0.680851 (-6400 900);
DISPLAY INVISIBLE (-6400 900);
FORCEPROP 1 LASTPIN (-6600 850) $PN 1
J 0
(-6588 862);
DISPLAY 0.489362 (-6588 862);
PAINT MONO (-6588 862);
FORCEPROP 1 LASTPIN (-6400 850) $PN 2
J 0
(-6438 862);
DISPLAY 0.489362 (-6438 862);
PAINT MONO (-6438 862);
FORCEPROP 1 LAST VALUE 33
J 2
(-6625 850);
DISPLAY 0.489362 (-6625 850);
PAINT SKYBLUE (-6625 850);
FORCEPROP 2 LAST ROOM RST_CPU0_PLD_TO_DIMM
J 2
(-6475 950);
DISPLAY 0.744681 (-6475 950);
PAINT RED (-6475 950);
DISPLAY INVISIBLE (-6475 950);
FORCEPROP 1 LAST PACK_TYPE 0402LF
J 2
(-6325 775);
DISPLAY 0.489362 (-6325 775);
PAINT SKYBLUE (-6325 775);
DISPLAY INVISIBLE (-6325 775);
FORCEPROP 1 LAST PART_NUMBER CS03302JB29
J 2
(-6400 900);
DISPLAY 0.489362 (-6400 900);
PAINT SKYBLUE (-6400 900);
DISPLAY INVISIBLE (-6400 900);
FORCEPROP 1 LAST TOLERANCE 5%
J 0
(-6625 825);
DISPLAY 0.489362 (-6625 825);
PAINT SKYBLUE (-6625 825);
DISPLAY INVISIBLE (-6625 825);
FORCEPROP 1 LAST MATERIAL CHIP
J 2
(-6325 825);
DISPLAY 0.489362 (-6325 825);
PAINT SKYBLUE (-6325 825);
DISPLAY INVISIBLE (-6325 825);
FORCEPROP 1 LAST WATTAGE 1/16W
J 2
(-6575 775);
DISPLAY 0.489362 (-6575 775);
PAINT SKYBLUE (-6575 775);
DISPLAY INVISIBLE (-6575 775);
FORCEPROP 1 LAST PATH I2108
J 0
(-6550 1000);
DISPLAY 0.978723 (-6550 1000);
PAINT WHITE (-6550 1000);
DISPLAY INVISIBLE (-6550 1000);
FORCEPROP 2 LAST BOM_COST MEM
J 2
(-6475 1000);
DISPLAY 0.744681 (-6475 1000);
PAINT WHITE (-6475 1000);
DISPLAY INVISIBLE (-6475 1000);
FORCEPROP 2 LAST CDS_LIB pure_quanta
J 0
(-6500 850);
DISPLAY INVISIBLE (-6500 850);
FORCEADD Q_RES..1
(-6500 700);
FORCEPROP 1 LAST LOCATION R482
J 0
(-6400 700);
DISPLAY 0.489362 (-6400 700);
PAINT SKYBLUE (-6400 700);
FORCEPROP 0 LAST $SEC 1
J 0
(-6400 750);
DISPLAY 0.680851 (-6400 750);
PAINT MONO (-6400 750);
DISPLAY INVISIBLE (-6400 750);
FORCEPROP 0 LAST CDS_SEC 1
J 0
(-6400 750);
DISPLAY 0.680851 (-6400 750);
DISPLAY INVISIBLE (-6400 750);
FORCEPROP 1 LASTPIN (-6600 700) $PN 1
J 0
(-6588 712);
DISPLAY 0.489362 (-6588 712);
PAINT MONO (-6588 712);
FORCEPROP 1 LASTPIN (-6400 700) $PN 2
J 0
(-6438 712);
DISPLAY 0.489362 (-6438 712);
PAINT MONO (-6438 712);
FORCEPROP 1 LAST VALUE 33
J 2
(-6625 700);
DISPLAY 0.489362 (-6625 700);
PAINT SKYBLUE (-6625 700);
FORCEPROP 2 LAST ROOM RST_CPU0_PLD_TO_DIMM
J 2
(-6475 800);
DISPLAY 0.744681 (-6475 800);
PAINT RED (-6475 800);
DISPLAY INVISIBLE (-6475 800);
FORCEPROP 1 LAST PACK_TYPE 0402LF
J 2
(-6325 625);
DISPLAY 0.489362 (-6325 625);
PAINT SKYBLUE (-6325 625);
DISPLAY INVISIBLE (-6325 625);
FORCEPROP 1 LAST PART_NUMBER CS03302JB29
J 2
(-6400 750);
DISPLAY 0.489362 (-6400 750);
PAINT SKYBLUE (-6400 750);
DISPLAY INVISIBLE (-6400 750);
FORCEPROP 1 LAST TOLERANCE 5%
J 0
(-6625 675);
DISPLAY 0.489362 (-6625 675);
PAINT SKYBLUE (-6625 675);
DISPLAY INVISIBLE (-6625 675);
FORCEPROP 1 LAST MATERIAL CHIP
J 2
(-6325 675);
DISPLAY 0.489362 (-6325 675);
PAINT SKYBLUE (-6325 675);
DISPLAY INVISIBLE (-6325 675);
FORCEPROP 1 LAST WATTAGE 1/16W
J 2
(-6575 625);
DISPLAY 0.489362 (-6575 625);
PAINT SKYBLUE (-6575 625);
DISPLAY INVISIBLE (-6575 625);
FORCEPROP 1 LAST PATH I2110
J 0
(-6550 850);
DISPLAY 0.978723 (-6550 850);
PAINT WHITE (-6550 850);
DISPLAY INVISIBLE (-6550 850);
FORCEPROP 2 LAST CDS_LIB pure_quanta
J 0
(-6500 700);
DISPLAY INVISIBLE (-6500 700);
FORCEPROP 2 LAST BOM_COST MEM
J 2
(-6475 850);
DISPLAY 0.744681 (-6475 850);
PAINT WHITE (-6475 850);
DISPLAY INVISIBLE (-6475 850);
FORCEADD OFFPAGE..1
(-7475 2450);
FORCEPROP 2 LAST $XR0 193 
J 0
(-7757 2450);
DISPLAY 0.638298 (-7757 2450);
PAINT MONO (-7757 2450);
FORCEPROP 2 LAST CDS_LIB standard
J 0
(-7475 2450);
DISPLAY INVISIBLE (-7475 2450);
FORCEPROP 2 LAST PATH I2111
J 0
(-7425 2525);
DISPLAY 0.680851 (-7425 2525);
DISPLAY INVISIBLE (-7425 2525);
FORCEPROP 1 LAST OFFPAGE TRUE
J 0
(-7150 2325);
DISPLAY 0.872340 (-7150 2325);
PAINT GREEN (-7150 2325);
DISPLAY INVISIBLE (-7150 2325);
FORCEPROP 1 LAST COMMENT_BODY TRUE
J 0
(-7350 2350);
DISPLAY 0.872340 (-7350 2350);
PAINT GREEN (-7350 2350);
DISPLAY INVISIBLE (-7350 2350);
FORCEADD OFFPAGE..1
(-7475 2300);
FORCEPROP 2 LAST $XR0 186 
J 0
(-7757 2300);
DISPLAY 0.638298 (-7757 2300);
PAINT MONO (-7757 2300);
FORCEPROP 2 LAST CDS_LIB standard
J 0
(-7475 2300);
DISPLAY INVISIBLE (-7475 2300);
FORCEPROP 1 LAST COMMENT_BODY TRUE
J 0
(-7350 2200);
DISPLAY 0.872340 (-7350 2200);
PAINT GREEN (-7350 2200);
DISPLAY INVISIBLE (-7350 2200);
FORCEPROP 1 LAST OFFPAGE TRUE
J 0
(-7150 2175);
DISPLAY 0.872340 (-7150 2175);
PAINT GREEN (-7150 2175);
DISPLAY INVISIBLE (-7150 2175);
FORCEPROP 2 LAST PATH I2112
J 0
(-7425 2375);
DISPLAY 0.680851 (-7425 2375);
DISPLAY INVISIBLE (-7425 2375);
FORCEADD OFFPAGE..1
(-7475 2150);
FORCEPROP 2 LAST $XR0 168 
J 0
(-7757 2150);
DISPLAY 0.638298 (-7757 2150);
PAINT MONO (-7757 2150);
FORCEPROP 1 LAST OFFPAGE TRUE
J 0
(-7150 2025);
DISPLAY 0.872340 (-7150 2025);
PAINT GREEN (-7150 2025);
DISPLAY INVISIBLE (-7150 2025);
FORCEPROP 1 LAST COMMENT_BODY TRUE
J 0
(-7350 2050);
DISPLAY 0.872340 (-7350 2050);
PAINT GREEN (-7350 2050);
DISPLAY INVISIBLE (-7350 2050);
FORCEPROP 2 LAST CDS_LIB standard
J 0
(-7475 2150);
DISPLAY INVISIBLE (-7475 2150);
FORCEPROP 2 LAST PATH I2113
J 0
(-7425 2225);
DISPLAY 0.680851 (-7425 2225);
DISPLAY INVISIBLE (-7425 2225);
FORCEADD OFFPAGE..1
(-7475 2200);
FORCEPROP 2 LAST $XR0 202 
J 0
(-7757 2200);
DISPLAY 0.638298 (-7757 2200);
PAINT MONO (-7757 2200);
FORCEPROP 2 LAST CDS_LIB standard
J 0
(-7475 2200);
DISPLAY INVISIBLE (-7475 2200);
FORCEPROP 1 LAST COMMENT_BODY TRUE
J 0
(-7350 2100);
DISPLAY 0.872340 (-7350 2100);
PAINT GREEN (-7350 2100);
DISPLAY INVISIBLE (-7350 2100);
FORCEPROP 1 LAST OFFPAGE TRUE
J 0
(-7150 2075);
DISPLAY 0.872340 (-7150 2075);
PAINT GREEN (-7150 2075);
DISPLAY INVISIBLE (-7150 2075);
FORCEPROP 2 LAST PATH I2114
J 0
(-7425 2275);
DISPLAY 0.680851 (-7425 2275);
DISPLAY INVISIBLE (-7425 2275);
FORCEADD OFFPAGE..5
(-7475 2000);
FORCEPROP 2 LAST $XR0 200 
J 0
(-7760 2000);
DISPLAY 0.638298 (-7760 2000);
PAINT MONO (-7760 2000);
FORCEPROP 2 LAST CDS_LIB standard
J 0
(-7475 2000);
DISPLAY INVISIBLE (-7475 2000);
FORCEPROP 1 LAST OFFPAGE TRUE
J 0
(-7150 1875);
DISPLAY 0.872340 (-7150 1875);
PAINT GREEN (-7150 1875);
DISPLAY INVISIBLE (-7150 1875);
FORCEPROP 1 LAST COMMENT_BODY TRUE
J 0
(-7375 1925);
DISPLAY 0.872340 (-7375 1925);
PAINT GREEN (-7375 1925);
DISPLAY INVISIBLE (-7375 1925);
FORCEPROP 2 LAST PATH I2115
J 0
(-7425 2075);
DISPLAY 0.680851 (-7425 2075);
DISPLAY INVISIBLE (-7425 2075);
FORCEADD OFFPAGE..1
(-7475 1950);
FORCEPROP 2 LAST $XR0 200 
J 0
(-7757 1950);
DISPLAY 0.638298 (-7757 1950);
PAINT MONO (-7757 1950);
FORCEPROP 2 LAST CDS_LIB standard
J 0
(-7475 1950);
DISPLAY INVISIBLE (-7475 1950);
FORCEPROP 1 LAST OFFPAGE TRUE
J 0
(-7150 1825);
DISPLAY 0.872340 (-7150 1825);
PAINT GREEN (-7150 1825);
DISPLAY INVISIBLE (-7150 1825);
FORCEPROP 1 LAST COMMENT_BODY TRUE
J 0
(-7350 1850);
DISPLAY 0.872340 (-7350 1850);
PAINT GREEN (-7350 1850);
DISPLAY INVISIBLE (-7350 1850);
FORCEPROP 2 LAST PATH I2116
J 0
(-7425 2025);
DISPLAY 0.680851 (-7425 2025);
DISPLAY INVISIBLE (-7425 2025);
FORCEADD OFFPAGE..5
(-7475 1900);
FORCEPROP 2 LAST $XR0 202 
J 0
(-7730 1900);
DISPLAY 0.638298 (-7730 1900);
PAINT MONO (-7730 1900);
FORCEPROP 2 LAST CDS_LIB standard
J 0
(-7475 1900);
DISPLAY INVISIBLE (-7475 1900);
FORCEPROP 1 LAST OFFPAGE TRUE
J 0
(-7150 1775);
DISPLAY 0.872340 (-7150 1775);
PAINT GREEN (-7150 1775);
DISPLAY INVISIBLE (-7150 1775);
FORCEPROP 1 LAST COMMENT_BODY TRUE
J 0
(-7375 1825);
DISPLAY 0.872340 (-7375 1825);
PAINT GREEN (-7375 1825);
DISPLAY INVISIBLE (-7375 1825);
FORCEPROP 2 LAST PATH I2117
J 0
(-7425 1975);
DISPLAY 0.680851 (-7425 1975);
DISPLAY INVISIBLE (-7425 1975);
FORCEADD OFFPAGE..1
(-7475 1800);
FORCEPROP 2 LAST $XR0 117 
J 0
(-7757 1800);
DISPLAY 0.638298 (-7757 1800);
PAINT MONO (-7757 1800);
FORCEPROP 1 LAST OFFPAGE TRUE
J 0
(-7150 1675);
DISPLAY 0.872340 (-7150 1675);
PAINT GREEN (-7150 1675);
DISPLAY INVISIBLE (-7150 1675);
FORCEPROP 1 LAST COMMENT_BODY TRUE
J 0
(-7350 1700);
DISPLAY 0.872340 (-7350 1700);
PAINT GREEN (-7350 1700);
DISPLAY INVISIBLE (-7350 1700);
FORCEPROP 2 LAST CDS_LIB standard
J 0
(-7475 1800);
DISPLAY INVISIBLE (-7475 1800);
FORCEPROP 2 LAST PATH I2118
J 0
(-7425 1875);
DISPLAY 0.680851 (-7425 1875);
DISPLAY INVISIBLE (-7425 1875);
FORCEADD OFFPAGE..6
(-7475 1750);
FORCEPROP 2 LAST $XR0 117 
J 0
(-7785 1750);
DISPLAY 0.638298 (-7785 1750);
PAINT MONO (-7785 1750);
FORCEPROP 2 LAST CDS_LIB standard
J 0
(-7475 1750);
DISPLAY INVISIBLE (-7475 1750);
FORCEPROP 1 LAST OFFPAGE TRUE
J 0
(-7150 1625);
DISPLAY 0.872340 (-7150 1625);
PAINT GREEN (-7150 1625);
DISPLAY INVISIBLE (-7150 1625);
FORCEPROP 1 LAST COMMENT_BODY TRUE
J 0
(-7375 1675);
DISPLAY 0.872340 (-7375 1675);
PAINT GREEN (-7375 1675);
DISPLAY INVISIBLE (-7375 1675);
FORCEPROP 2 LAST PATH I2119
J 0
(-7425 1825);
DISPLAY 0.680851 (-7425 1825);
DISPLAY INVISIBLE (-7425 1825);
FORCEADD OFFPAGE..1
(-7475 1650);
FORCEPROP 2 LAST $XR1 167 
J 0
(-7877 1650);
DISPLAY 0.638298 (-7877 1650);
PAINT MONO (-7877 1650);
FORCEPROP 2 LAST $XR0 166 
J 0
(-7757 1650);
DISPLAY 0.638298 (-7757 1650);
PAINT MONO (-7757 1650);
FORCEPROP 2 LAST CDS_LIB standard
J 0
(-7475 1650);
DISPLAY INVISIBLE (-7475 1650);
FORCEPROP 1 LAST OFFPAGE TRUE
J 0
(-7150 1525);
DISPLAY 0.872340 (-7150 1525);
PAINT GREEN (-7150 1525);
DISPLAY INVISIBLE (-7150 1525);
FORCEPROP 1 LAST COMMENT_BODY TRUE
J 0
(-7350 1550);
DISPLAY 0.872340 (-7350 1550);
PAINT GREEN (-7350 1550);
DISPLAY INVISIBLE (-7350 1550);
FORCEPROP 2 LAST PATH I2120
J 0
(-7425 1725);
DISPLAY 0.680851 (-7425 1725);
DISPLAY INVISIBLE (-7425 1725);
FORCEADD OFFPAGE..5
(-7475 1700);
FORCEPROP 2 LAST $XR0 168 
J 0
(-7760 1700);
DISPLAY 0.638298 (-7760 1700);
PAINT MONO (-7760 1700);
FORCEPROP 2 LAST CDS_LIB standard
J 0
(-7475 1700);
DISPLAY INVISIBLE (-7475 1700);
FORCEPROP 1 LAST OFFPAGE TRUE
J 0
(-7150 1575);
DISPLAY 0.872340 (-7150 1575);
PAINT GREEN (-7150 1575);
DISPLAY INVISIBLE (-7150 1575);
FORCEPROP 1 LAST COMMENT_BODY TRUE
J 0
(-7375 1625);
DISPLAY 0.872340 (-7375 1625);
PAINT GREEN (-7375 1625);
DISPLAY INVISIBLE (-7375 1625);
FORCEPROP 2 LAST PATH I2121
J 0
(-7425 1775);
DISPLAY 0.680851 (-7425 1775);
DISPLAY INVISIBLE (-7425 1775);
FORCEADD OFFPAGE..5
(-7475 1600);
FORCEPROP 2 LAST $XR0 185 
J 0
(-7730 1600);
DISPLAY 0.638298 (-7730 1600);
PAINT MONO (-7730 1600);
FORCEPROP 2 LAST CDS_LIB standard
J 0
(-7475 1600);
DISPLAY INVISIBLE (-7475 1600);
FORCEPROP 1 LAST OFFPAGE TRUE
J 0
(-7150 1475);
DISPLAY 0.872340 (-7150 1475);
PAINT GREEN (-7150 1475);
DISPLAY INVISIBLE (-7150 1475);
FORCEPROP 1 LAST COMMENT_BODY TRUE
J 0
(-7375 1525);
DISPLAY 0.872340 (-7375 1525);
PAINT GREEN (-7375 1525);
DISPLAY INVISIBLE (-7375 1525);
FORCEPROP 2 LAST PATH I2122
J 0
(-7425 1675);
DISPLAY 0.680851 (-7425 1675);
DISPLAY INVISIBLE (-7425 1675);
FORCEADD OFFPAGE..1
(-7475 1550);
FORCEPROP 2 LAST $XR0 185 
J 0
(-7757 1550);
DISPLAY 0.638298 (-7757 1550);
PAINT MONO (-7757 1550);
FORCEPROP 1 LAST OFFPAGE TRUE
J 0
(-7150 1425);
DISPLAY 0.872340 (-7150 1425);
PAINT GREEN (-7150 1425);
DISPLAY INVISIBLE (-7150 1425);
FORCEPROP 1 LAST COMMENT_BODY TRUE
J 0
(-7350 1450);
DISPLAY 0.872340 (-7350 1450);
PAINT GREEN (-7350 1450);
DISPLAY INVISIBLE (-7350 1450);
FORCEPROP 2 LAST CDS_LIB standard
J 0
(-7475 1550);
DISPLAY INVISIBLE (-7475 1550);
FORCEPROP 2 LAST PATH I2123
J 0
(-7425 1625);
DISPLAY 0.680851 (-7425 1625);
DISPLAY INVISIBLE (-7425 1625);
FORCEADD OFFPAGE..1
(-7475 1500);
FORCEPROP 2 LAST $XR0 167 
J 0
(-7757 1500);
DISPLAY 0.638298 (-7757 1500);
PAINT MONO (-7757 1500);
FORCEPROP 2 LAST CDS_LIB standard
J 0
(-7475 1500);
DISPLAY INVISIBLE (-7475 1500);
FORCEPROP 1 LAST OFFPAGE TRUE
J 0
(-7150 1375);
DISPLAY 0.872340 (-7150 1375);
PAINT GREEN (-7150 1375);
DISPLAY INVISIBLE (-7150 1375);
FORCEPROP 1 LAST COMMENT_BODY TRUE
J 0
(-7350 1400);
DISPLAY 0.872340 (-7350 1400);
PAINT GREEN (-7350 1400);
DISPLAY INVISIBLE (-7350 1400);
FORCEPROP 2 LAST PATH I2124
J 0
(-7425 1575);
DISPLAY 0.680851 (-7425 1575);
DISPLAY INVISIBLE (-7425 1575);
FORCEADD OFFPAGE..5
(-7475 1400);
FORCEPROP 2 LAST $XR0 193 
J 0
(-7730 1400);
DISPLAY 0.638298 (-7730 1400);
PAINT MONO (-7730 1400);
FORCEPROP 2 LAST CDS_LIB standard
J 0
(-7475 1400);
DISPLAY INVISIBLE (-7475 1400);
FORCEPROP 1 LAST OFFPAGE TRUE
J 0
(-7150 1275);
DISPLAY 0.872340 (-7150 1275);
PAINT GREEN (-7150 1275);
DISPLAY INVISIBLE (-7150 1275);
FORCEPROP 1 LAST COMMENT_BODY TRUE
J 0
(-7375 1325);
DISPLAY 0.872340 (-7375 1325);
PAINT GREEN (-7375 1325);
DISPLAY INVISIBLE (-7375 1325);
FORCEPROP 2 LAST PATH I2125
J 0
(-7425 1475);
DISPLAY 0.680851 (-7425 1475);
DISPLAY INVISIBLE (-7425 1475);
FORCEADD OFFPAGE..5
(-7475 1450);
FORCEPROP 2 LAST $XR0 28 
J 0
(-7699 1450);
DISPLAY 0.638298 (-7699 1450);
PAINT MONO (-7699 1450);
FORCEPROP 2 LAST CDS_LIB standard
J 0
(-7475 1450);
DISPLAY INVISIBLE (-7475 1450);
FORCEPROP 1 LAST OFFPAGE TRUE
J 0
(-7150 1325);
DISPLAY 0.872340 (-7150 1325);
PAINT GREEN (-7150 1325);
DISPLAY INVISIBLE (-7150 1325);
FORCEPROP 1 LAST COMMENT_BODY TRUE
J 0
(-7375 1375);
DISPLAY 0.872340 (-7375 1375);
PAINT GREEN (-7375 1375);
DISPLAY INVISIBLE (-7375 1375);
FORCEPROP 2 LAST PATH I2126
J 0
(-7425 1525);
DISPLAY 0.680851 (-7425 1525);
DISPLAY INVISIBLE (-7425 1525);
FORCEADD OFFPAGE..1
(-7475 1350);
FORCEPROP 2 LAST $XR0 193 
J 0
(-7757 1350);
DISPLAY 0.638298 (-7757 1350);
PAINT MONO (-7757 1350);
FORCEPROP 1 LAST OFFPAGE TRUE
J 0
(-7150 1225);
DISPLAY 0.872340 (-7150 1225);
PAINT GREEN (-7150 1225);
DISPLAY INVISIBLE (-7150 1225);
FORCEPROP 1 LAST COMMENT_BODY TRUE
J 0
(-7350 1250);
DISPLAY 0.872340 (-7350 1250);
PAINT GREEN (-7350 1250);
DISPLAY INVISIBLE (-7350 1250);
FORCEPROP 2 LAST CDS_LIB standard
J 0
(-7475 1350);
DISPLAY INVISIBLE (-7475 1350);
FORCEPROP 2 LAST PATH I2127
J 0
(-7425 1425);
DISPLAY 0.680851 (-7425 1425);
DISPLAY INVISIBLE (-7425 1425);
FORCEADD OFFPAGE..1
(-7475 1300);
FORCEPROP 2 LAST $XR1 125 
J 0
(-7877 1300);
DISPLAY 0.638298 (-7877 1300);
PAINT MONO (-7877 1300);
FORCEPROP 2 LAST $XR0 206 
J 0
(-7757 1300);
DISPLAY 0.638298 (-7757 1300);
PAINT MONO (-7757 1300);
FORCEPROP 2 LAST CDS_LIB standard
J 0
(-7475 1300);
DISPLAY INVISIBLE (-7475 1300);
FORCEPROP 1 LAST COMMENT_BODY TRUE
J 0
(-7350 1200);
DISPLAY 0.872340 (-7350 1200);
PAINT GREEN (-7350 1200);
DISPLAY INVISIBLE (-7350 1200);
FORCEPROP 1 LAST OFFPAGE TRUE
J 0
(-7150 1175);
DISPLAY 0.872340 (-7150 1175);
PAINT GREEN (-7150 1175);
DISPLAY INVISIBLE (-7150 1175);
FORCEPROP 2 LAST PATH I2128
J 0
(-7425 1375);
DISPLAY 0.680851 (-7425 1375);
DISPLAY INVISIBLE (-7425 1375);
FORCEADD OFFPAGE..1
(-7475 1250);
FORCEPROP 2 LAST $XR0 205 
J 0
(-7757 1250);
DISPLAY 0.638298 (-7757 1250);
PAINT MONO (-7757 1250);
FORCEPROP 2 LAST CDS_LIB standard
J 0
(-7475 1250);
DISPLAY INVISIBLE (-7475 1250);
FORCEPROP 1 LAST OFFPAGE TRUE
J 0
(-7150 1125);
DISPLAY 0.872340 (-7150 1125);
PAINT GREEN (-7150 1125);
DISPLAY INVISIBLE (-7150 1125);
FORCEPROP 1 LAST COMMENT_BODY TRUE
J 0
(-7350 1150);
DISPLAY 0.872340 (-7350 1150);
PAINT GREEN (-7350 1150);
DISPLAY INVISIBLE (-7350 1150);
FORCEPROP 2 LAST PATH I2129
J 0
(-7425 1325);
DISPLAY 0.680851 (-7425 1325);
DISPLAY INVISIBLE (-7425 1325);
FORCEADD OFFPAGE..1
(-7475 1200);
FORCEPROP 2 LAST $XR0 206 
J 0
(-7757 1200);
DISPLAY 0.638298 (-7757 1200);
PAINT MONO (-7757 1200);
FORCEPROP 2 LAST CDS_LIB standard
J 0
(-7475 1200);
DISPLAY INVISIBLE (-7475 1200);
FORCEPROP 1 LAST OFFPAGE TRUE
J 0
(-7150 1075);
DISPLAY 0.872340 (-7150 1075);
PAINT GREEN (-7150 1075);
DISPLAY INVISIBLE (-7150 1075);
FORCEPROP 1 LAST COMMENT_BODY TRUE
J 0
(-7350 1100);
DISPLAY 0.872340 (-7350 1100);
PAINT GREEN (-7350 1100);
DISPLAY INVISIBLE (-7350 1100);
FORCEPROP 2 LAST PATH I2130
J 0
(-7425 1275);
DISPLAY 0.680851 (-7425 1275);
DISPLAY INVISIBLE (-7425 1275);
FORCEADD OFFPAGE..5
(-7475 1150);
FORCEPROP 2 LAST $XR0 123 
J 0
(-7730 1150);
DISPLAY 0.638298 (-7730 1150);
PAINT MONO (-7730 1150);
FORCEPROP 2 LAST CDS_LIB standard
J 0
(-7475 1150);
DISPLAY INVISIBLE (-7475 1150);
FORCEPROP 1 LAST OFFPAGE TRUE
J 0
(-7150 1025);
DISPLAY 0.872340 (-7150 1025);
PAINT GREEN (-7150 1025);
DISPLAY INVISIBLE (-7150 1025);
FORCEPROP 1 LAST COMMENT_BODY TRUE
J 0
(-7375 1075);
DISPLAY 0.872340 (-7375 1075);
PAINT GREEN (-7375 1075);
DISPLAY INVISIBLE (-7375 1075);
FORCEPROP 2 LAST PATH I2131
J 0
(-7425 1225);
DISPLAY 0.680851 (-7425 1225);
DISPLAY INVISIBLE (-7425 1225);
FORCEADD OFFPAGE..5
(-7475 1050);
FORCEPROP 2 LAST $XR0 84 
J 0
(-7699 1050);
DISPLAY 0.638298 (-7699 1050);
PAINT MONO (-7699 1050);
FORCEPROP 2 LAST CDS_LIB standard
J 0
(-7475 1050);
DISPLAY INVISIBLE (-7475 1050);
FORCEPROP 1 LAST OFFPAGE TRUE
J 0
(-7150 925);
DISPLAY 0.872340 (-7150 925);
PAINT GREEN (-7150 925);
DISPLAY INVISIBLE (-7150 925);
FORCEPROP 1 LAST COMMENT_BODY TRUE
J 0
(-7375 975);
DISPLAY 0.872340 (-7375 975);
PAINT GREEN (-7375 975);
DISPLAY INVISIBLE (-7375 975);
FORCEPROP 2 LAST PATH I2133
J 0
(-7425 1125);
DISPLAY 0.680851 (-7425 1125);
DISPLAY INVISIBLE (-7425 1125);
FORCEADD OFFPAGE..5
(-7475 900);
FORCEPROP 2 LAST $XR0 84 
J 0
(-7699 900);
DISPLAY 0.638298 (-7699 900);
PAINT MONO (-7699 900);
FORCEPROP 1 LAST OFFPAGE TRUE
J 0
(-7150 775);
DISPLAY 0.872340 (-7150 775);
PAINT GREEN (-7150 775);
DISPLAY INVISIBLE (-7150 775);
FORCEPROP 1 LAST COMMENT_BODY TRUE
J 0
(-7375 825);
DISPLAY 0.872340 (-7375 825);
PAINT GREEN (-7375 825);
DISPLAY INVISIBLE (-7375 825);
FORCEPROP 2 LAST CDS_LIB standard
J 0
(-7475 900);
DISPLAY INVISIBLE (-7475 900);
FORCEPROP 2 LAST PATH I2135
J 0
(-7425 975);
DISPLAY 0.680851 (-7425 975);
DISPLAY INVISIBLE (-7425 975);
FORCEADD OFFPAGE..5
(-7475 850);
FORCEPROP 2 LAST $XR0 125 
J 0
(-7730 850);
DISPLAY 0.638298 (-7730 850);
PAINT MONO (-7730 850);
FORCEPROP 2 LAST CDS_LIB standard
J 0
(-7475 850);
DISPLAY INVISIBLE (-7475 850);
FORCEPROP 1 LAST OFFPAGE TRUE
J 0
(-7150 725);
DISPLAY 0.872340 (-7150 725);
PAINT GREEN (-7150 725);
DISPLAY INVISIBLE (-7150 725);
FORCEPROP 1 LAST COMMENT_BODY TRUE
J 0
(-7375 775);
DISPLAY 0.872340 (-7375 775);
PAINT GREEN (-7375 775);
DISPLAY INVISIBLE (-7375 775);
FORCEPROP 2 LAST PATH I2136
J 0
(-7425 925);
DISPLAY 0.680851 (-7425 925);
DISPLAY INVISIBLE (-7425 925);
FORCEADD OFFPAGE..5
(-7475 750);
FORCEPROP 2 LAST $XR1 205 
J 0
(-7819 750);
DISPLAY 0.638298 (-7819 750);
PAINT MONO (-7819 750);
FORCEPROP 2 LAST $XR0 82 
J 0
(-7699 750);
DISPLAY 0.638298 (-7699 750);
PAINT MONO (-7699 750);
FORCEPROP 2 LAST CDS_LIB standard
J 0
(-7475 750);
DISPLAY INVISIBLE (-7475 750);
FORCEPROP 1 LAST OFFPAGE TRUE
J 0
(-7150 625);
DISPLAY 0.872340 (-7150 625);
PAINT GREEN (-7150 625);
DISPLAY INVISIBLE (-7150 625);
FORCEPROP 1 LAST COMMENT_BODY TRUE
J 0
(-7375 675);
DISPLAY 0.872340 (-7375 675);
PAINT GREEN (-7375 675);
DISPLAY INVISIBLE (-7375 675);
FORCEPROP 2 LAST PATH I2137
J 0
(-7425 825);
DISPLAY 0.680851 (-7425 825);
DISPLAY INVISIBLE (-7425 825);
FORCEADD OFFPAGE..1
(-7475 800);
FORCEPROP 2 LAST $XR1 124 
J 0
(-7877 800);
DISPLAY 0.638298 (-7877 800);
PAINT MONO (-7877 800);
FORCEPROP 2 LAST $XR0 205 
J 0
(-7757 800);
DISPLAY 0.638298 (-7757 800);
PAINT MONO (-7757 800);
FORCEPROP 2 LAST CDS_LIB standard
J 0
(-7475 800);
DISPLAY INVISIBLE (-7475 800);
FORCEPROP 1 LAST COMMENT_BODY TRUE
J 0
(-7350 700);
DISPLAY 0.872340 (-7350 700);
PAINT GREEN (-7350 700);
DISPLAY INVISIBLE (-7350 700);
FORCEPROP 1 LAST OFFPAGE TRUE
J 0
(-7150 675);
DISPLAY 0.872340 (-7150 675);
PAINT GREEN (-7150 675);
DISPLAY INVISIBLE (-7150 675);
FORCEPROP 2 LAST PATH I2138
J 0
(-7425 875);
DISPLAY 0.680851 (-7425 875);
DISPLAY INVISIBLE (-7425 875);
FORCEADD OFFPAGE..5
(-7475 700);
FORCEPROP 2 LAST $XR1 206 
J 0
(-7819 700);
DISPLAY 0.638298 (-7819 700);
PAINT MONO (-7819 700);
FORCEPROP 2 LAST $XR0 82 
J 0
(-7699 700);
DISPLAY 0.638298 (-7699 700);
PAINT MONO (-7699 700);
FORCEPROP 2 LAST CDS_LIB standard
J 0
(-7475 700);
DISPLAY INVISIBLE (-7475 700);
FORCEPROP 1 LAST OFFPAGE TRUE
J 0
(-7150 575);
DISPLAY 0.872340 (-7150 575);
PAINT GREEN (-7150 575);
DISPLAY INVISIBLE (-7150 575);
FORCEPROP 1 LAST COMMENT_BODY TRUE
J 0
(-7375 625);
DISPLAY 0.872340 (-7375 625);
PAINT GREEN (-7375 625);
DISPLAY INVISIBLE (-7375 625);
FORCEPROP 2 LAST PATH I2139
J 0
(-7425 775);
DISPLAY 0.680851 (-7425 775);
DISPLAY INVISIBLE (-7425 775);
FORCEADD OFFPAGE..1
(-7475 600);
FORCEPROP 2 LAST $XR0 207 
J 0
(-7757 600);
DISPLAY 0.638298 (-7757 600);
PAINT MONO (-7757 600);
FORCEPROP 2 LAST CDS_LIB standard
J 0
(-7475 600);
DISPLAY INVISIBLE (-7475 600);
FORCEPROP 1 LAST COMMENT_BODY TRUE
J 0
(-7350 500);
DISPLAY 0.872340 (-7350 500);
PAINT GREEN (-7350 500);
DISPLAY INVISIBLE (-7350 500);
FORCEPROP 1 LAST OFFPAGE TRUE
J 0
(-7150 475);
DISPLAY 0.872340 (-7150 475);
PAINT GREEN (-7150 475);
DISPLAY INVISIBLE (-7150 475);
FORCEPROP 2 LAST PATH I2140
J 0
(-7425 675);
DISPLAY 0.680851 (-7425 675);
DISPLAY INVISIBLE (-7425 675);
FORCEADD OFFPAGE..5
(-7475 500);
FORCEPROP 2 LAST $XR0 160 
J 0
(-7730 500);
DISPLAY 0.638298 (-7730 500);
PAINT MONO (-7730 500);
FORCEPROP 2 LAST CDS_LIB standard
J 0
(-7475 500);
DISPLAY INVISIBLE (-7475 500);
FORCEPROP 1 LAST COMMENT_BODY TRUE
J 0
(-7375 425);
DISPLAY 0.872340 (-7375 425);
PAINT GREEN (-7375 425);
DISPLAY INVISIBLE (-7375 425);
FORCEPROP 1 LAST OFFPAGE TRUE
J 0
(-7150 375);
DISPLAY 0.872340 (-7150 375);
PAINT GREEN (-7150 375);
DISPLAY INVISIBLE (-7150 375);
FORCEPROP 2 LAST PATH I2141
J 0
(-7425 575);
DISPLAY 0.680851 (-7425 575);
DISPLAY INVISIBLE (-7425 575);
FORCEADD OFFPAGE..1
(-7450 550);
FORCEPROP 2 LAST $XR1 126 
J 0
(-7852 550);
DISPLAY 0.638298 (-7852 550);
PAINT MONO (-7852 550);
FORCEPROP 2 LAST $XR0 207 
J 0
(-7732 550);
DISPLAY 0.638298 (-7732 550);
PAINT MONO (-7732 550);
FORCEPROP 2 LAST CDS_LIB standard
J 0
(-7450 550);
DISPLAY INVISIBLE (-7450 550);
FORCEPROP 1 LAST COMMENT_BODY TRUE
J 0
(-7325 450);
DISPLAY 0.872340 (-7325 450);
PAINT GREEN (-7325 450);
DISPLAY INVISIBLE (-7325 450);
FORCEPROP 1 LAST OFFPAGE TRUE
J 0
(-7125 425);
DISPLAY 0.872340 (-7125 425);
PAINT GREEN (-7125 425);
DISPLAY INVISIBLE (-7125 425);
FORCEPROP 2 LAST PATH I2142
J 0
(-7400 625);
DISPLAY 0.680851 (-7400 625);
DISPLAY INVISIBLE (-7400 625);
FORCEADD Q_RES..1
(-6500 450);
FORCEPROP 1 LAST LOCATION R1052
J 0
(-6400 450);
DISPLAY 0.489362 (-6400 450);
PAINT SKYBLUE (-6400 450);
FORCEPROP 0 LAST $SEC 1
J 0
(-6400 500);
DISPLAY 0.680851 (-6400 500);
PAINT MONO (-6400 500);
DISPLAY INVISIBLE (-6400 500);
FORCEPROP 0 LAST CDS_SEC 1
J 0
(-6400 500);
DISPLAY 0.680851 (-6400 500);
DISPLAY INVISIBLE (-6400 500);
FORCEPROP 1 LASTPIN (-6600 450) $PN 1
J 0
(-6588 462);
DISPLAY 0.489362 (-6588 462);
PAINT MONO (-6588 462);
FORCEPROP 1 LASTPIN (-6400 450) $PN 2
J 0
(-6438 462);
DISPLAY 0.489362 (-6438 462);
PAINT MONO (-6438 462);
FORCEPROP 1 LAST VALUE 33
J 2
(-6625 450);
DISPLAY 0.489362 (-6625 450);
PAINT SKYBLUE (-6625 450);
FORCEPROP 2 LAST ROOM RST_CPU0_PLD_TO_DIMM
J 2
(-6475 550);
DISPLAY 0.744681 (-6475 550);
PAINT RED (-6475 550);
DISPLAY INVISIBLE (-6475 550);
FORCEPROP 1 LAST PACK_TYPE 0402LF
J 2
(-6325 375);
DISPLAY 0.489362 (-6325 375);
PAINT SKYBLUE (-6325 375);
DISPLAY INVISIBLE (-6325 375);
FORCEPROP 1 LAST PART_NUMBER CS03302JB29
J 2
(-6400 500);
DISPLAY 0.489362 (-6400 500);
PAINT SKYBLUE (-6400 500);
DISPLAY INVISIBLE (-6400 500);
FORCEPROP 1 LAST TOLERANCE 5%
J 0
(-6625 425);
DISPLAY 0.489362 (-6625 425);
PAINT SKYBLUE (-6625 425);
DISPLAY INVISIBLE (-6625 425);
FORCEPROP 1 LAST MATERIAL CHIP
J 2
(-6325 425);
DISPLAY 0.489362 (-6325 425);
PAINT SKYBLUE (-6325 425);
DISPLAY INVISIBLE (-6325 425);
FORCEPROP 1 LAST WATTAGE 1/16W
J 2
(-6575 375);
DISPLAY 0.489362 (-6575 375);
PAINT SKYBLUE (-6575 375);
DISPLAY INVISIBLE (-6575 375);
FORCEPROP 1 LAST PATH I2143
J 0
(-6550 600);
DISPLAY 0.978723 (-6550 600);
PAINT WHITE (-6550 600);
DISPLAY INVISIBLE (-6550 600);
FORCEPROP 2 LAST BOM_COST MEM
J 2
(-6475 600);
DISPLAY 0.744681 (-6475 600);
PAINT WHITE (-6475 600);
DISPLAY INVISIBLE (-6475 600);
FORCEPROP 2 LAST CDS_LIB pure_quanta
J 0
(-6500 450);
DISPLAY INVISIBLE (-6500 450);
FORCEADD LCMXO3D9400HC5BG484C..2
(-4425 1675);
FORCEPROP 1 LAST LOCATION U18
J 0
(-5145 3338);
DISPLAY 0.489362 (-5145 3338);
PAINT SKYBLUE (-5145 3338);
FORCEPROP 0 LAST $SEC 2
J 0
(-5125 3475);
DISPLAY 0.680851 (-5125 3475);
PAINT MONO (-5125 3475);
DISPLAY INVISIBLE (-5125 3475);
FORCEPROP 0 LAST CDS_SEC 2
J 0
(-5125 3475);
DISPLAY 0.680851 (-5125 3475);
DISPLAY INVISIBLE (-5125 3475);
FORCEPROP 0 LASTPIN (-5300 3000) $PN AA2
J 2
(-5310 3010);
DISPLAY 0.489362 (-5310 3010);
PAINT MONO (-5310 3010);
FORCEPROP 0 LASTPIN (-5300 2950) $PN AB2
J 2
(-5310 2960);
DISPLAY 0.489362 (-5310 2960);
PAINT MONO (-5310 2960);
FORCEPROP 0 LASTPIN (-5300 2900) $PN V6
J 2
(-5310 2910);
DISPLAY 0.489362 (-5310 2910);
PAINT MONO (-5310 2910);
FORCEPROP 0 LASTPIN (-5300 2850) $PN U6
J 2
(-5310 2860);
DISPLAY 0.489362 (-5310 2860);
PAINT MONO (-5310 2860);
FORCEPROP 0 LASTPIN (-5300 2800) $PN AA3
J 2
(-5310 2810);
DISPLAY 0.489362 (-5310 2810);
PAINT MONO (-5310 2810);
FORCEPROP 0 LASTPIN (-5300 2750) $PN AB3
J 2
(-5310 2760);
DISPLAY 0.489362 (-5310 2760);
PAINT MONO (-5310 2760);
FORCEPROP 0 LASTPIN (-5300 2700) $PN Y4
J 2
(-5310 2710);
DISPLAY 0.489362 (-5310 2710);
PAINT MONO (-5310 2710);
FORCEPROP 0 LASTPIN (-5300 2650) $PN W5
J 2
(-5310 2660);
DISPLAY 0.489362 (-5310 2660);
PAINT MONO (-5310 2660);
FORCEPROP 0 LASTPIN (-5300 2600) $PN AA4
J 2
(-5310 2610);
DISPLAY 0.489362 (-5310 2610);
PAINT MONO (-5310 2610);
FORCEPROP 0 LASTPIN (-5300 2550) $PN AB4
J 2
(-5310 2560);
DISPLAY 0.489362 (-5310 2560);
PAINT MONO (-5310 2560);
FORCEPROP 0 LASTPIN (-5300 2500) $PN U7
J 2
(-5310 2510);
DISPLAY 0.489362 (-5310 2510);
PAINT MONO (-5310 2510);
FORCEPROP 0 LASTPIN (-5300 2450) $PN T8
J 2
(-5310 2460);
DISPLAY 0.489362 (-5310 2460);
PAINT MONO (-5310 2460);
FORCEPROP 0 LASTPIN (-5300 2400) $PN AA5
J 2
(-5310 2410);
DISPLAY 0.489362 (-5310 2410);
PAINT MONO (-5310 2410);
FORCEPROP 0 LASTPIN (-5300 2350) $PN AB5
J 2
(-5310 2360);
DISPLAY 0.489362 (-5310 2360);
PAINT MONO (-5310 2360);
FORCEPROP 0 LASTPIN (-5300 2300) $PN Y5
J 2
(-5310 2310);
DISPLAY 0.489362 (-5310 2310);
PAINT MONO (-5310 2310);
FORCEPROP 0 LASTPIN (-5300 2250) $PN Y6
J 2
(-5310 2260);
DISPLAY 0.489362 (-5310 2260);
PAINT MONO (-5310 2260);
FORCEPROP 0 LASTPIN (-5300 2200) $PN AA6
J 2
(-5310 2210);
DISPLAY 0.489362 (-5310 2210);
PAINT MONO (-5310 2210);
FORCEPROP 0 LASTPIN (-5300 2150) $PN AB6
J 2
(-5310 2160);
DISPLAY 0.489362 (-5310 2160);
PAINT MONO (-5310 2160);
FORCEPROP 0 LASTPIN (-5300 2100) $PN W6
J 2
(-5310 2110);
DISPLAY 0.489362 (-5310 2110);
PAINT MONO (-5310 2110);
FORCEPROP 0 LASTPIN (-5300 2050) $PN V7
J 2
(-5310 2060);
DISPLAY 0.489362 (-5310 2060);
PAINT MONO (-5310 2060);
FORCEPROP 0 LASTPIN (-5300 2000) $PN AA7
J 2
(-5310 2010);
DISPLAY 0.489362 (-5310 2010);
PAINT MONO (-5310 2010);
FORCEPROP 0 LASTPIN (-5300 1950) $PN AB7
J 2
(-5310 1960);
DISPLAY 0.489362 (-5310 1960);
PAINT MONO (-5310 1960);
FORCEPROP 0 LASTPIN (-5300 1900) $PN V8
J 2
(-5310 1910);
DISPLAY 0.489362 (-5310 1910);
PAINT MONO (-5310 1910);
FORCEPROP 0 LASTPIN (-5300 1850) $PN U8
J 2
(-5310 1860);
DISPLAY 0.489362 (-5310 1860);
PAINT MONO (-5310 1860);
FORCEPROP 0 LASTPIN (-5300 1800) $PN T9
J 2
(-5310 1810);
DISPLAY 0.489362 (-5310 1810);
PAINT MONO (-5310 1810);
FORCEPROP 0 LASTPIN (-5300 1750) $PN U9
J 2
(-5310 1760);
DISPLAY 0.489362 (-5310 1760);
PAINT MONO (-5310 1760);
FORCEPROP 0 LASTPIN (-5300 1700) $PN V9
J 2
(-5310 1710);
DISPLAY 0.489362 (-5310 1710);
PAINT MONO (-5310 1710);
FORCEPROP 0 LASTPIN (-5300 1650) $PN W8
J 2
(-5310 1660);
DISPLAY 0.489362 (-5310 1660);
PAINT MONO (-5310 1660);
FORCEPROP 0 LASTPIN (-5300 1600) $PN AA8
J 2
(-5310 1610);
DISPLAY 0.489362 (-5310 1610);
PAINT MONO (-5310 1610);
FORCEPROP 0 LASTPIN (-5300 1550) $PN AB8
J 2
(-5310 1560);
DISPLAY 0.489362 (-5310 1560);
PAINT MONO (-5310 1560);
FORCEPROP 0 LASTPIN (-5300 1500) $PN Y8
J 2
(-5310 1510);
DISPLAY 0.489362 (-5310 1510);
PAINT MONO (-5310 1510);
FORCEPROP 0 LASTPIN (-5300 1450) $PN W9
J 2
(-5310 1460);
DISPLAY 0.489362 (-5310 1460);
PAINT MONO (-5310 1460);
FORCEPROP 0 LASTPIN (-5300 1400) $PN AA9
J 2
(-5310 1410);
DISPLAY 0.489362 (-5310 1410);
PAINT MONO (-5310 1410);
FORCEPROP 0 LASTPIN (-5300 1350) $PN AB9
J 2
(-5310 1360);
DISPLAY 0.489362 (-5310 1360);
PAINT MONO (-5310 1360);
FORCEPROP 0 LASTPIN (-5300 1300) $PN T10
J 2
(-5310 1310);
DISPLAY 0.489362 (-5310 1310);
PAINT MONO (-5310 1310);
FORCEPROP 0 LASTPIN (-5300 1250) $PN U10
J 2
(-5310 1260);
DISPLAY 0.489362 (-5310 1260);
PAINT MONO (-5310 1260);
FORCEPROP 0 LASTPIN (-5300 1200) $PN V10
J 2
(-5310 1210);
DISPLAY 0.489362 (-5310 1210);
PAINT MONO (-5310 1210);
FORCEPROP 0 LASTPIN (-5300 1150) $PN W10
J 2
(-5310 1160);
DISPLAY 0.489362 (-5310 1160);
PAINT MONO (-5310 1160);
FORCEPROP 0 LASTPIN (-5300 1100) $PN Y9
J 2
(-5310 1110);
DISPLAY 0.489362 (-5310 1110);
PAINT MONO (-5310 1110);
FORCEPROP 0 LASTPIN (-5300 1050) $PN Y10
J 2
(-5310 1060);
DISPLAY 0.489362 (-5310 1060);
PAINT MONO (-5310 1060);
FORCEPROP 0 LASTPIN (-5300 950) $PN AA10
J 2
(-5310 960);
DISPLAY 0.489362 (-5310 960);
PAINT MONO (-5310 960);
FORCEPROP 0 LASTPIN (-5300 900) $PN AB10
J 2
(-5310 910);
DISPLAY 0.489362 (-5310 910);
PAINT MONO (-5310 910);
FORCEPROP 0 LASTPIN (-5300 850) $PN T11
J 2
(-5310 860);
DISPLAY 0.489362 (-5310 860);
PAINT MONO (-5310 860);
FORCEPROP 0 LASTPIN (-5300 800) $PN U11
J 2
(-5310 810);
DISPLAY 0.489362 (-5310 810);
PAINT MONO (-5310 810);
FORCEPROP 0 LASTPIN (-5300 750) $PN AA11
J 2
(-5310 760);
DISPLAY 0.489362 (-5310 760);
PAINT MONO (-5310 760);
FORCEPROP 0 LASTPIN (-5300 700) $PN AB11
J 2
(-5310 710);
DISPLAY 0.489362 (-5310 710);
PAINT MONO (-5310 710);
FORCEPROP 0 LASTPIN (-5300 650) $PN V11
J 2
(-5310 660);
DISPLAY 0.489362 (-5310 660);
PAINT MONO (-5310 660);
FORCEPROP 0 LASTPIN (-5300 600) $PN Y11
J 2
(-5310 610);
DISPLAY 0.489362 (-5310 610);
PAINT MONO (-5310 610);
FORCEPROP 0 LASTPIN (-5300 550) $PN Y12
J 2
(-5310 560);
DISPLAY 0.489362 (-5310 560);
PAINT MONO (-5310 560);
FORCEPROP 0 LASTPIN (-5300 500) $PN T12
J 2
(-5310 510);
DISPLAY 0.489362 (-5310 510);
PAINT MONO (-5310 510);
FORCEPROP 0 LASTPIN (-5300 450) $PN U12
J 2
(-5310 460);
DISPLAY 0.489362 (-5310 460);
PAINT MONO (-5310 460);
FORCEPROP 0 LASTPIN (-5300 400) $PN V12
J 2
(-5310 410);
DISPLAY 0.489362 (-5310 410);
PAINT MONO (-5310 410);
FORCEPROP 0 LASTPIN (-3550 2800) $PN AB12
J 0
(-3540 2810);
DISPLAY 0.489362 (-3540 2810);
PAINT MONO (-3540 2810);
FORCEPROP 0 LASTPIN (-3550 2750) $PN AA12
J 0
(-3540 2760);
DISPLAY 0.489362 (-3540 2760);
PAINT MONO (-3540 2760);
FORCEPROP 0 LASTPIN (-3550 2700) $PN V13
J 0
(-3540 2710);
DISPLAY 0.489362 (-3540 2710);
PAINT MONO (-3540 2710);
FORCEPROP 0 LASTPIN (-3550 2650) $PN U13
J 0
(-3540 2660);
DISPLAY 0.489362 (-3540 2660);
PAINT MONO (-3540 2660);
FORCEPROP 0 LASTPIN (-3550 2600) $PN AB13
J 0
(-3540 2610);
DISPLAY 0.489362 (-3540 2610);
PAINT MONO (-3540 2610);
FORCEPROP 0 LASTPIN (-3550 2550) $PN AA13
J 0
(-3540 2560);
DISPLAY 0.489362 (-3540 2560);
PAINT MONO (-3540 2560);
FORCEPROP 0 LASTPIN (-3550 2500) $PN Y13
J 0
(-3540 2510);
DISPLAY 0.489362 (-3540 2510);
PAINT MONO (-3540 2510);
FORCEPROP 0 LASTPIN (-3550 2450) $PN W13
J 0
(-3540 2460);
DISPLAY 0.489362 (-3540 2460);
PAINT MONO (-3540 2460);
FORCEPROP 0 LASTPIN (-3550 2400) $PN T13
J 0
(-3540 2410);
DISPLAY 0.489362 (-3540 2410);
PAINT MONO (-3540 2410);
FORCEPROP 0 LASTPIN (-3550 2350) $PN T14
J 0
(-3540 2360);
DISPLAY 0.489362 (-3540 2360);
PAINT MONO (-3540 2360);
FORCEPROP 0 LASTPIN (-3550 2300) $PN U14
J 0
(-3540 2310);
DISPLAY 0.489362 (-3540 2310);
PAINT MONO (-3540 2310);
FORCEPROP 0 LASTPIN (-3550 2250) $PN V14
J 0
(-3540 2260);
DISPLAY 0.489362 (-3540 2260);
PAINT MONO (-3540 2260);
FORCEPROP 0 LASTPIN (-3550 2200) $PN AB14
J 0
(-3540 2210);
DISPLAY 0.489362 (-3540 2210);
PAINT MONO (-3540 2210);
FORCEPROP 0 LASTPIN (-3550 2150) $PN AA14
J 0
(-3540 2160);
DISPLAY 0.489362 (-3540 2160);
PAINT MONO (-3540 2160);
FORCEPROP 0 LASTPIN (-3550 2100) $PN Y14
J 0
(-3540 2110);
DISPLAY 0.489362 (-3540 2110);
PAINT MONO (-3540 2110);
FORCEPROP 0 LASTPIN (-3550 2050) $PN W14
J 0
(-3540 2060);
DISPLAY 0.489362 (-3540 2060);
PAINT MONO (-3540 2060);
FORCEPROP 0 LASTPIN (-3550 2000) $PN AB15
J 0
(-3540 2010);
DISPLAY 0.489362 (-3540 2010);
PAINT MONO (-3540 2010);
FORCEPROP 0 LASTPIN (-3550 1950) $PN AA15
J 0
(-3540 1960);
DISPLAY 0.489362 (-3540 1960);
PAINT MONO (-3540 1960);
FORCEPROP 0 LASTPIN (-3550 1900) $PN Y15
J 0
(-3540 1910);
DISPLAY 0.489362 (-3540 1910);
PAINT MONO (-3540 1910);
FORCEPROP 0 LASTPIN (-3550 1850) $PN W15
J 0
(-3540 1860);
DISPLAY 0.489362 (-3540 1860);
PAINT MONO (-3540 1860);
FORCEPROP 0 LASTPIN (-3550 1800) $PN AB16
J 0
(-3540 1810);
DISPLAY 0.489362 (-3540 1810);
PAINT MONO (-3540 1810);
FORCEPROP 0 LASTPIN (-3550 1750) $PN AA16
J 0
(-3540 1760);
DISPLAY 0.489362 (-3540 1760);
PAINT MONO (-3540 1760);
FORCEPROP 0 LASTPIN (-3550 1700) $PN V15
J 0
(-3540 1710);
DISPLAY 0.489362 (-3540 1710);
PAINT MONO (-3540 1710);
FORCEPROP 0 LASTPIN (-3550 1650) $PN U15
J 0
(-3540 1660);
DISPLAY 0.489362 (-3540 1660);
PAINT MONO (-3540 1660);
FORCEPROP 0 LASTPIN (-3550 1600) $PN AB17
J 0
(-3540 1610);
DISPLAY 0.489362 (-3540 1610);
PAINT MONO (-3540 1610);
FORCEPROP 0 LASTPIN (-3550 1550) $PN AA17
J 0
(-3540 1560);
DISPLAY 0.489362 (-3540 1560);
PAINT MONO (-3540 1560);
FORCEPROP 0 LASTPIN (-3550 1500) $PN Y17
J 0
(-3540 1510);
DISPLAY 0.489362 (-3540 1510);
PAINT MONO (-3540 1510);
FORCEPROP 0 LASTPIN (-3550 1450) $PN V16
J 0
(-3540 1460);
DISPLAY 0.489362 (-3540 1460);
PAINT MONO (-3540 1460);
FORCEPROP 0 LASTPIN (-3550 1400) $PN AB18
J 0
(-3540 1410);
DISPLAY 0.489362 (-3540 1410);
PAINT MONO (-3540 1410);
FORCEPROP 0 LASTPIN (-3550 1350) $PN AA18
J 0
(-3540 1360);
DISPLAY 0.489362 (-3540 1360);
PAINT MONO (-3540 1360);
FORCEPROP 0 LASTPIN (-3550 1300) $PN Y18
J 0
(-3540 1310);
DISPLAY 0.489362 (-3540 1310);
PAINT MONO (-3540 1310);
FORCEPROP 0 LASTPIN (-3550 1250) $PN W17
J 0
(-3540 1260);
DISPLAY 0.489362 (-3540 1260);
PAINT MONO (-3540 1260);
FORCEPROP 0 LASTPIN (-3550 1200) $PN AB19
J 0
(-3540 1210);
DISPLAY 0.489362 (-3540 1210);
PAINT MONO (-3540 1210);
FORCEPROP 0 LASTPIN (-3550 1150) $PN AA19
J 0
(-3540 1160);
DISPLAY 0.489362 (-3540 1160);
PAINT MONO (-3540 1160);
FORCEPROP 0 LASTPIN (-3550 1100) $PN T15
J 0
(-3540 1110);
DISPLAY 0.489362 (-3540 1110);
PAINT MONO (-3540 1110);
FORCEPROP 0 LASTPIN (-3550 1050) $PN U16
J 0
(-3540 1060);
DISPLAY 0.489362 (-3540 1060);
PAINT MONO (-3540 1060);
FORCEPROP 0 LASTPIN (-3550 1000) $PN AB20
J 0
(-3540 1010);
DISPLAY 0.489362 (-3540 1010);
PAINT MONO (-3540 1010);
FORCEPROP 0 LASTPIN (-3550 950) $PN AA20
J 0
(-3540 960);
DISPLAY 0.489362 (-3540 960);
PAINT MONO (-3540 960);
FORCEPROP 0 LASTPIN (-3550 900) $PN Y19
J 0
(-3540 910);
DISPLAY 0.489362 (-3540 910);
PAINT MONO (-3540 910);
FORCEPROP 0 LASTPIN (-3550 850) $PN W18
J 0
(-3540 860);
DISPLAY 0.489362 (-3540 860);
PAINT MONO (-3540 860);
FORCEPROP 0 LASTPIN (-3550 800) $PN AB21
J 0
(-3540 810);
DISPLAY 0.489362 (-3540 810);
PAINT MONO (-3540 810);
FORCEPROP 0 LASTPIN (-3550 750) $PN AA21
J 0
(-3540 760);
DISPLAY 0.489362 (-3540 760);
PAINT MONO (-3540 760);
FORCEPROP 0 LASTPIN (-3550 700) $PN V17
J 0
(-3540 710);
DISPLAY 0.489362 (-3540 710);
PAINT MONO (-3540 710);
FORCEPROP 0 LASTPIN (-3550 650) $PN T16
J 0
(-3540 660);
DISPLAY 0.489362 (-3540 660);
PAINT MONO (-3540 660);
FORCEPROP 2 LAST VALUE LCMXO3D-9400HC-5BG484C
J 0
(-5145 3385);
DISPLAY 0.489362 (-5145 3385);
PAINT SKYBLUE (-5145 3385);
FORCEPROP 1 LAST MATERIAL IC
J 0
(-5145 3064);
DISPLAY 0.489362 (-5145 3064);
PAINT SKYBLUE (-5145 3064);
FORCEPROP 2 LAST PART_TYPE SMLF
J 0
(-5145 3430);
DISPLAY 0.680851 (-5145 3430);
FORCEPROP 1 LAST PART_NUMBER AJ094000T05
J 0
(-5145 3191);
DISPLAY 0.489362 (-5145 3191);
PAINT SKYBLUE (-5145 3191);
FORCEPROP 1 LAST PATH I2144
J 0
(-4425 1675);
DISPLAY 0.723404 (-4425 1675);
PAINT GREEN (-4425 1675);
DISPLAY INVISIBLE (-4425 1675);
FORCEPROP 2 LAST CDS_LIB pure_quanta
J 0
(-4425 1675);
DISPLAY INVISIBLE (-4425 1675);
FORCEPROP 1 LAST NEEDS_NO_SIZE TRUE
J 0
(-4425 1675);
DISPLAY 0.723404 (-4425 1675);
PAINT GREEN (-4425 1675);
DISPLAY INVISIBLE (-4425 1675);
FORCEPROP 1 LAST CDS_LMAN_SYM_OUTLINE -725,1375,725,-1375
J 0
(-4425 1675);
DISPLAY 0.468085 (-4425 1675);
PAINT GREEN (-4425 1675);
DISPLAY INVISIBLE (-4425 1675);
FORCEADD Q_RES..1
(-6500 400);
FORCEPROP 1 LAST LOCATION R648
J 0
(-6400 400);
DISPLAY 0.489362 (-6400 400);
PAINT SKYBLUE (-6400 400);
FORCEPROP 0 LAST $SEC 1
J 0
(-6400 450);
DISPLAY 0.680851 (-6400 450);
PAINT MONO (-6400 450);
DISPLAY INVISIBLE (-6400 450);
FORCEPROP 0 LAST CDS_SEC 1
J 0
(-6400 450);
DISPLAY 0.680851 (-6400 450);
DISPLAY INVISIBLE (-6400 450);
FORCEPROP 1 LASTPIN (-6600 400) $PN 1
J 0
(-6588 412);
DISPLAY 0.489362 (-6588 412);
PAINT MONO (-6588 412);
FORCEPROP 1 LASTPIN (-6400 400) $PN 2
J 0
(-6438 412);
DISPLAY 0.489362 (-6438 412);
PAINT MONO (-6438 412);
FORCEPROP 1 LAST VALUE 33
J 2
(-6625 400);
DISPLAY 0.489362 (-6625 400);
PAINT SKYBLUE (-6625 400);
FORCEPROP 2 LAST ROOM RST_CPU0_PLD_TO_DIMM
J 2
(-6475 500);
DISPLAY 0.744681 (-6475 500);
PAINT RED (-6475 500);
DISPLAY INVISIBLE (-6475 500);
FORCEPROP 1 LAST PACK_TYPE 0402LF
J 2
(-6325 325);
DISPLAY 0.489362 (-6325 325);
PAINT SKYBLUE (-6325 325);
DISPLAY INVISIBLE (-6325 325);
FORCEPROP 1 LAST PART_NUMBER CS03302JB29
J 2
(-6400 450);
DISPLAY 0.489362 (-6400 450);
PAINT SKYBLUE (-6400 450);
DISPLAY INVISIBLE (-6400 450);
FORCEPROP 1 LAST TOLERANCE 5%
J 0
(-6625 375);
DISPLAY 0.489362 (-6625 375);
PAINT SKYBLUE (-6625 375);
DISPLAY INVISIBLE (-6625 375);
FORCEPROP 1 LAST MATERIAL CHIP
J 2
(-6325 375);
DISPLAY 0.489362 (-6325 375);
PAINT SKYBLUE (-6325 375);
DISPLAY INVISIBLE (-6325 375);
FORCEPROP 1 LAST WATTAGE 1/16W
J 2
(-6575 325);
DISPLAY 0.489362 (-6575 325);
PAINT SKYBLUE (-6575 325);
DISPLAY INVISIBLE (-6575 325);
FORCEPROP 1 LAST PATH I2145
J 0
(-6550 550);
DISPLAY 0.978723 (-6550 550);
PAINT WHITE (-6550 550);
DISPLAY INVISIBLE (-6550 550);
FORCEPROP 2 LAST BOM_COST MEM
J 2
(-6475 550);
DISPLAY 0.744681 (-6475 550);
PAINT WHITE (-6475 550);
DISPLAY INVISIBLE (-6475 550);
FORCEPROP 2 LAST CDS_LIB pure_quanta
J 0
(-6500 400);
DISPLAY INVISIBLE (-6500 400);
FORCEADD OFFPAGE..5
(-7475 450);
FORCEPROP 2 LAST $XR0 124 
J 0
(-7730 450);
DISPLAY 0.638298 (-7730 450);
PAINT MONO (-7730 450);
FORCEPROP 2 LAST CDS_LIB standard
J 0
(-7475 450);
DISPLAY INVISIBLE (-7475 450);
FORCEPROP 1 LAST COMMENT_BODY TRUE
J 0
(-7375 375);
DISPLAY 0.872340 (-7375 375);
PAINT GREEN (-7375 375);
DISPLAY INVISIBLE (-7375 375);
FORCEPROP 1 LAST OFFPAGE TRUE
J 0
(-7150 325);
DISPLAY 0.872340 (-7150 325);
PAINT GREEN (-7150 325);
DISPLAY INVISIBLE (-7150 325);
FORCEPROP 2 LAST PATH I2146
J 0
(-7425 525);
DISPLAY 0.680851 (-7425 525);
DISPLAY INVISIBLE (-7425 525);
FORCEADD OFFPAGE..5
(-7475 400);
FORCEPROP 2 LAST $XR1 205 
J 0
(-7819 400);
DISPLAY 0.638298 (-7819 400);
PAINT MONO (-7819 400);
FORCEPROP 2 LAST $XR0 82 
J 0
(-7699 400);
DISPLAY 0.638298 (-7699 400);
PAINT MONO (-7699 400);
FORCEPROP 2 LAST CDS_LIB standard
J 0
(-7475 400);
DISPLAY INVISIBLE (-7475 400);
FORCEPROP 1 LAST COMMENT_BODY TRUE
J 0
(-7375 325);
DISPLAY 0.872340 (-7375 325);
PAINT GREEN (-7375 325);
DISPLAY INVISIBLE (-7375 325);
FORCEPROP 1 LAST OFFPAGE TRUE
J 0
(-7150 275);
DISPLAY 0.872340 (-7150 275);
PAINT GREEN (-7150 275);
DISPLAY INVISIBLE (-7150 275);
FORCEPROP 2 LAST PATH I2147
J 0
(-7425 475);
DISPLAY 0.680851 (-7425 475);
DISPLAY INVISIBLE (-7425 475);
FORCEADD OFFPAGE..1
(-7475 2550);
FORCEPROP 2 LAST $XR1 61 
J 0
(-7847 2550);
DISPLAY 0.638298 (-7847 2550);
PAINT MONO (-7847 2550);
FORCEPROP 2 LAST $XR0 115 
J 0
(-7757 2550);
DISPLAY 0.638298 (-7757 2550);
PAINT MONO (-7757 2550);
FORCEPROP 2 LAST PATH I2148
J 0
(-7425 2625);
DISPLAY 0.680851 (-7425 2625);
DISPLAY INVISIBLE (-7425 2625);
FORCEPROP 1 LAST COMMENT_BODY TRUE
J 0
(-7350 2450);
DISPLAY 0.872340 (-7350 2450);
PAINT GREEN (-7350 2450);
DISPLAY INVISIBLE (-7350 2450);
FORCEPROP 1 LAST OFFPAGE TRUE
J 0
(-7150 2425);
DISPLAY 0.872340 (-7150 2425);
PAINT GREEN (-7150 2425);
DISPLAY INVISIBLE (-7150 2425);
FORCEPROP 2 LAST CDS_LIB standard
J 0
(-7475 2550);
DISPLAY INVISIBLE (-7475 2550);
FORCEADD OFFPAGE..1
(-7475 2600);
FORCEPROP 2 LAST $XR0 158 
J 0
(-7757 2600);
DISPLAY 0.638298 (-7757 2600);
PAINT MONO (-7757 2600);
FORCEPROP 2 LAST PATH I2149
J 0
(-7425 2675);
DISPLAY 0.680851 (-7425 2675);
DISPLAY INVISIBLE (-7425 2675);
FORCEPROP 1 LAST OFFPAGE TRUE
J 0
(-7150 2475);
DISPLAY 0.872340 (-7150 2475);
PAINT GREEN (-7150 2475);
DISPLAY INVISIBLE (-7150 2475);
FORCEPROP 1 LAST COMMENT_BODY TRUE
J 0
(-7350 2500);
DISPLAY 0.872340 (-7350 2500);
PAINT GREEN (-7350 2500);
DISPLAY INVISIBLE (-7350 2500);
FORCEPROP 2 LAST CDS_LIB standard
J 0
(-7475 2600);
DISPLAY INVISIBLE (-7475 2600);
FORCEADD OFFPAGE..4
R 2
(-7475 2750);
FORCEPROP 2 LAST $XR1 169 
J 0
(-7846 2750);
DISPLAY 0.638298 (-7846 2750);
PAINT MONO (-7846 2750);
FORCEPROP 2 LAST $XR0 82 
J 0
(-7726 2750);
DISPLAY 0.638298 (-7726 2750);
PAINT MONO (-7726 2750);
FORCEPROP 2 LAST PATH I2150
J 0
(-7425 2825);
DISPLAY 0.680851 (-7425 2825);
DISPLAY INVISIBLE (-7425 2825);
FORCEPROP 2 LAST CDS_LIB standard
J 0
(-7475 2750);
DISPLAY INVISIBLE (-7475 2750);
FORCEPROP 1 LAST OFFPAGE TRUE
J 2
(-7800 2625);
DISPLAY 0.872340 (-7800 2625);
PAINT GREEN (-7800 2625);
DISPLAY INVISIBLE (-7800 2625);
FORCEPROP 1 LAST COMMENT_BODY TRUE
J 2
(-7450 2650);
DISPLAY 0.872340 (-7450 2650);
PAINT GREEN (-7450 2650);
DISPLAY INVISIBLE (-7450 2650);
FORCEADD OFFPAGE..4
R 2
(-7475 2800);
FORCEPROP 2 LAST $XR0 120 
J 0
(-7757 2800);
DISPLAY 0.638298 (-7757 2800);
PAINT MONO (-7757 2800);
FORCEPROP 2 LAST PATH I2151
J 0
(-7425 2875);
DISPLAY 0.680851 (-7425 2875);
DISPLAY INVISIBLE (-7425 2875);
FORCEPROP 2 LAST CDS_LIB standard
J 0
(-7475 2800);
DISPLAY INVISIBLE (-7475 2800);
FORCEPROP 1 LAST OFFPAGE TRUE
J 2
(-7800 2675);
DISPLAY 0.872340 (-7800 2675);
PAINT GREEN (-7800 2675);
DISPLAY INVISIBLE (-7800 2675);
FORCEPROP 1 LAST COMMENT_BODY TRUE
J 2
(-7450 2700);
DISPLAY 0.872340 (-7450 2700);
PAINT GREEN (-7450 2700);
DISPLAY INVISIBLE (-7450 2700);
FORCEADD OFFPAGE..1
R 2
(-1400 1000);
FORCEPROP 2 LAST $XR1 149 
J 0
(-1124 1000);
DISPLAY 0.638298 (-1124 1000);
PAINT MONO (-1124 1000);
FORCEPROP 2 LAST $XR0 82 
J 0
(-1214 1000);
DISPLAY 0.638298 (-1214 1000);
PAINT MONO (-1214 1000);
FORCEPROP 1 LAST COMMENT_BODY TRUE
J 2
(-1525 900);
DISPLAY 0.872340 (-1525 900);
PAINT GREEN (-1525 900);
DISPLAY INVISIBLE (-1525 900);
FORCEPROP 1 LAST OFFPAGE TRUE
J 2
(-1725 875);
DISPLAY 0.872340 (-1725 875);
PAINT GREEN (-1725 875);
DISPLAY INVISIBLE (-1725 875);
FORCEPROP 2 LAST PATH I2152
J 0
(-1225 1075);
DISPLAY 0.680851 (-1225 1075);
DISPLAY INVISIBLE (-1225 1075);
FORCEPROP 2 LAST CDS_LIB standard
J 0
(-1400 1000);
DISPLAY INVISIBLE (-1400 1000);
FORCEADD OFFPAGE..5
(-7500 2400);
FORCEPROP 2 LAST $XR0 143 
J 0
(-7785 2400);
DISPLAY 0.638298 (-7785 2400);
PAINT MONO (-7785 2400);
FORCEPROP 2 LAST CDS_LIB standard
J 0
(-7500 2400);
DISPLAY INVISIBLE (-7500 2400);
FORCEPROP 2 LAST PATH I2153
J 0
(-7450 2475);
DISPLAY 0.680851 (-7450 2475);
DISPLAY INVISIBLE (-7450 2475);
FORCEPROP 1 LAST OFFPAGE TRUE
J 0
(-7175 2275);
DISPLAY 0.872340 (-7175 2275);
PAINT GREEN (-7175 2275);
DISPLAY INVISIBLE (-7175 2275);
FORCEPROP 1 LAST COMMENT_BODY TRUE
J 0
(-7400 2325);
DISPLAY 0.872340 (-7400 2325);
PAINT GREEN (-7400 2325);
DISPLAY INVISIBLE (-7400 2325);
FORCEADD OFFPAGE..5
(-7500 2350);
FORCEPROP 2 LAST $XR0 143 
J 0
(-7785 2350);
DISPLAY 0.638298 (-7785 2350);
PAINT MONO (-7785 2350);
FORCEPROP 1 LAST COMMENT_BODY TRUE
J 0
(-7400 2275);
DISPLAY 0.872340 (-7400 2275);
PAINT GREEN (-7400 2275);
DISPLAY INVISIBLE (-7400 2275);
FORCEPROP 1 LAST OFFPAGE TRUE
J 0
(-7175 2225);
DISPLAY 0.872340 (-7175 2225);
PAINT GREEN (-7175 2225);
DISPLAY INVISIBLE (-7175 2225);
FORCEPROP 2 LAST PATH I2154
J 0
(-7450 2425);
DISPLAY 0.680851 (-7450 2425);
DISPLAY INVISIBLE (-7450 2425);
FORCEPROP 2 LAST CDS_LIB standard
J 0
(-7500 2350);
DISPLAY INVISIBLE (-7500 2350);
FORCEADD OFFPAGE..5
(-7500 2100);
FORCEPROP 2 LAST $XR0 143 
J 0
(-7785 2100);
DISPLAY 0.638298 (-7785 2100);
PAINT MONO (-7785 2100);
FORCEPROP 1 LAST OFFPAGE TRUE
J 0
(-7175 1975);
DISPLAY 0.872340 (-7175 1975);
PAINT GREEN (-7175 1975);
DISPLAY INVISIBLE (-7175 1975);
FORCEPROP 1 LAST COMMENT_BODY TRUE
J 0
(-7400 2025);
DISPLAY 0.872340 (-7400 2025);
PAINT GREEN (-7400 2025);
DISPLAY INVISIBLE (-7400 2025);
FORCEPROP 2 LAST PATH I2155
J 0
(-7450 2175);
DISPLAY 0.680851 (-7450 2175);
DISPLAY INVISIBLE (-7450 2175);
FORCEPROP 2 LAST CDS_LIB standard
J 0
(-7500 2100);
DISPLAY INVISIBLE (-7500 2100);
FORCEADD OFFPAGE..5
(-7500 2050);
FORCEPROP 2 LAST $XR0 143 
J 0
(-7785 2050);
DISPLAY 0.638298 (-7785 2050);
PAINT MONO (-7785 2050);
FORCEPROP 1 LAST COMMENT_BODY TRUE
J 0
(-7400 1975);
DISPLAY 0.872340 (-7400 1975);
PAINT GREEN (-7400 1975);
DISPLAY INVISIBLE (-7400 1975);
FORCEPROP 1 LAST OFFPAGE TRUE
J 0
(-7175 1925);
DISPLAY 0.872340 (-7175 1925);
PAINT GREEN (-7175 1925);
DISPLAY INVISIBLE (-7175 1925);
FORCEPROP 2 LAST PATH I2156
J 0
(-7450 2125);
DISPLAY 0.680851 (-7450 2125);
DISPLAY INVISIBLE (-7450 2125);
FORCEPROP 2 LAST CDS_LIB standard
J 0
(-7500 2050);
DISPLAY INVISIBLE (-7500 2050);
FORCEADD OFFPAGE..2
(-1375 1600);
FORCEPROP 2 LAST $XR0 143 
J 0
(-1186 1600);
DISPLAY 0.638298 (-1186 1600);
PAINT MONO (-1186 1600);
FORCEPROP 2 LAST CDS_LIB standard
J 0
(-1375 1600);
DISPLAY INVISIBLE (-1375 1600);
FORCEPROP 2 LAST PATH I2157
J 0
(-1200 1675);
DISPLAY 0.680851 (-1200 1675);
DISPLAY INVISIBLE (-1200 1675);
FORCEPROP 1 LAST COMMENT_BODY TRUE
J 0
(-1420 1505);
DISPLAY 0.872340 (-1420 1505);
PAINT GREEN (-1420 1505);
DISPLAY INVISIBLE (-1420 1505);
FORCEPROP 1 LAST OFFPAGE TRUE
J 0
(-1050 1475);
DISPLAY 0.872340 (-1050 1475);
PAINT GREEN (-1050 1475);
DISPLAY INVISIBLE (-1050 1475);
FORCEADD OFFPAGE..2
(-1375 1550);
FORCEPROP 2 LAST $XR0 143 
J 0
(-1186 1550);
DISPLAY 0.638298 (-1186 1550);
PAINT MONO (-1186 1550);
FORCEPROP 2 LAST CDS_LIB standard
J 0
(-1375 1550);
DISPLAY INVISIBLE (-1375 1550);
FORCEPROP 2 LAST PATH I2158
J 0
(-1200 1625);
DISPLAY 0.680851 (-1200 1625);
DISPLAY INVISIBLE (-1200 1625);
FORCEPROP 1 LAST OFFPAGE TRUE
J 0
(-1050 1425);
DISPLAY 0.872340 (-1050 1425);
PAINT GREEN (-1050 1425);
DISPLAY INVISIBLE (-1050 1425);
FORCEPROP 1 LAST COMMENT_BODY TRUE
J 0
(-1420 1455);
DISPLAY 0.872340 (-1420 1455);
PAINT GREEN (-1420 1455);
DISPLAY INVISIBLE (-1420 1455);
FORCEADD OFFPAGE..2
(-1375 1400);
FORCEPROP 2 LAST $XR0 143 
J 0
(-1186 1400);
DISPLAY 0.638298 (-1186 1400);
PAINT MONO (-1186 1400);
FORCEPROP 2 LAST CDS_LIB standard
J 0
(-1375 1400);
DISPLAY INVISIBLE (-1375 1400);
FORCEPROP 2 LAST PATH I2159
J 0
(-1200 1475);
DISPLAY 0.680851 (-1200 1475);
DISPLAY INVISIBLE (-1200 1475);
FORCEPROP 1 LAST OFFPAGE TRUE
J 0
(-1050 1275);
DISPLAY 0.872340 (-1050 1275);
PAINT GREEN (-1050 1275);
DISPLAY INVISIBLE (-1050 1275);
FORCEPROP 1 LAST COMMENT_BODY TRUE
J 0
(-1420 1305);
DISPLAY 0.872340 (-1420 1305);
PAINT GREEN (-1420 1305);
DISPLAY INVISIBLE (-1420 1305);
FORCEADD OFFPAGE..2
(-1375 1350);
FORCEPROP 2 LAST $XR0 143 
J 0
(-1186 1350);
DISPLAY 0.638298 (-1186 1350);
PAINT MONO (-1186 1350);
FORCEPROP 2 LAST CDS_LIB standard
J 0
(-1375 1350);
DISPLAY INVISIBLE (-1375 1350);
FORCEPROP 2 LAST PATH I2160
J 0
(-1200 1425);
DISPLAY 0.680851 (-1200 1425);
DISPLAY INVISIBLE (-1200 1425);
FORCEPROP 1 LAST OFFPAGE TRUE
J 0
(-1050 1225);
DISPLAY 0.872340 (-1050 1225);
PAINT GREEN (-1050 1225);
DISPLAY INVISIBLE (-1050 1225);
FORCEPROP 1 LAST COMMENT_BODY TRUE
J 0
(-1420 1255);
DISPLAY 0.872340 (-1420 1255);
PAINT GREEN (-1420 1255);
DISPLAY INVISIBLE (-1420 1255);
FORCEADD OFFPAGE..2
(-2225 5400);
FORCEPROP 2 LAST $XR0 144 
J 0
(-2036 5400);
DISPLAY 0.638298 (-2036 5400);
PAINT MONO (-2036 5400);
FORCEPROP 1 LAST OFFPAGE TRUE
J 0
(-1900 5275);
DISPLAY 0.872340 (-1900 5275);
PAINT GREEN (-1900 5275);
DISPLAY INVISIBLE (-1900 5275);
FORCEPROP 1 LAST COMMENT_BODY TRUE
J 0
(-2270 5305);
DISPLAY 0.872340 (-2270 5305);
PAINT GREEN (-2270 5305);
DISPLAY INVISIBLE (-2270 5305);
FORCEPROP 2 LAST PATH I2161
J 0
(-2050 5475);
DISPLAY 0.680851 (-2050 5475);
DISPLAY INVISIBLE (-2050 5475);
FORCEPROP 2 LAST CDS_LIB standard
J 0
(-2225 5400);
DISPLAY INVISIBLE (-2225 5400);
FORCEADD Q_RES..1
(-2550 2800);
FORCEPROP 1 LAST $LOCATION R745
J 0
(-2450 2800);
DISPLAY 0.489362 (-2450 2800);
PAINT SKYBLUE (-2450 2800);
FORCEPROP 0 LAST CDS_LOCATION R745
J 0
(-2450 2825);
DISPLAY 0.680851 (-2450 2825);
DISPLAY INVISIBLE (-2450 2825);
FORCEPROP 0 LAST $SEC 1
J 0
(-2450 2825);
DISPLAY 0.680851 (-2450 2825);
PAINT MONO (-2450 2825);
DISPLAY INVISIBLE (-2450 2825);
FORCEPROP 0 LAST CDS_SEC 1
J 0
(-2450 2825);
DISPLAY 0.680851 (-2450 2825);
DISPLAY INVISIBLE (-2450 2825);
FORCEPROP 1 LASTPIN (-2650 2800) $PN 1
J 0
(-2638 2812);
DISPLAY 0.787234 (-2638 2812);
PAINT MONO (-2638 2812);
FORCEPROP 1 LASTPIN (-2450 2800) $PN 2
J 0
(-2488 2812);
DISPLAY 0.787234 (-2488 2812);
PAINT MONO (-2488 2812);
FORCEPROP 1 LAST VALUE 0
J 2
(-2675 2800);
DISPLAY 0.489362 (-2675 2800);
PAINT SKYBLUE (-2675 2800);
FORCEPROP 2 LAST CDS_LIB pure_quanta
J 0
(-2550 2800);
DISPLAY INVISIBLE (-2550 2800);
FORCEPROP 1 LAST PATH I2162
J 0
(-2600 2950);
DISPLAY 0.978723 (-2600 2950);
PAINT WHITE (-2600 2950);
DISPLAY INVISIBLE (-2600 2950);
FORCEPROP 2 LAST BOM_COST MEM
J 2
(-2525 2950);
DISPLAY 0.744681 (-2525 2950);
PAINT WHITE (-2525 2950);
DISPLAY INVISIBLE (-2525 2950);
FORCEPROP 1 LAST WATTAGE 1/16W
J 2
(-2625 2725);
DISPLAY 0.489362 (-2625 2725);
PAINT SKYBLUE (-2625 2725);
DISPLAY INVISIBLE (-2625 2725);
FORCEPROP 1 LAST MATERIAL CHIP
J 2
(-2375 2775);
DISPLAY 0.489362 (-2375 2775);
PAINT SKYBLUE (-2375 2775);
DISPLAY INVISIBLE (-2375 2775);
FORCEPROP 1 LAST TOLERANCE 5%
J 0
(-2675 2775);
DISPLAY 0.489362 (-2675 2775);
PAINT SKYBLUE (-2675 2775);
DISPLAY INVISIBLE (-2675 2775);
FORCEPROP 1 LAST PART_NUMBER CS00002JB38
J 2
(-2450 2850);
DISPLAY 0.489362 (-2450 2850);
PAINT SKYBLUE (-2450 2850);
DISPLAY INVISIBLE (-2450 2850);
FORCEPROP 1 LAST PACK_TYPE 0402LF
J 2
(-2375 2725);
DISPLAY 0.489362 (-2375 2725);
PAINT SKYBLUE (-2375 2725);
DISPLAY INVISIBLE (-2375 2725);
FORCEPROP 2 LAST ROOM RST_CPU0_PLD_TO_DIMM
J 2
(-2525 2900);
DISPLAY 0.744681 (-2525 2900);
PAINT RED (-2525 2900);
DISPLAY INVISIBLE (-2525 2900);
FORCEADD OFFPAGE..1
R 2
(-1375 2800);
FORCEPROP 2 LAST $XR1 114 
J 0
(-1099 2800);
DISPLAY 0.638298 (-1099 2800);
PAINT MONO (-1099 2800);
FORCEPROP 2 LAST $XR0 82 
J 0
(-1189 2800);
DISPLAY 0.638298 (-1189 2800);
PAINT MONO (-1189 2800);
FORCEPROP 2 LAST CDS_LIB standard
J 0
(-1375 2800);
DISPLAY INVISIBLE (-1375 2800);
FORCEPROP 2 LAST PATH I2163
J 0
(-1200 2875);
DISPLAY 0.680851 (-1200 2875);
DISPLAY INVISIBLE (-1200 2875);
FORCEPROP 1 LAST COMMENT_BODY TRUE
J 2
(-1500 2700);
DISPLAY 0.872340 (-1500 2700);
PAINT GREEN (-1500 2700);
DISPLAY INVISIBLE (-1500 2700);
FORCEPROP 1 LAST OFFPAGE TRUE
J 2
(-1700 2675);
DISPLAY 0.872340 (-1700 2675);
PAINT GREEN (-1700 2675);
DISPLAY INVISIBLE (-1700 2675);
FORCEADD Q_RES..1
(-2550 2650);
FORCEPROP 1 LAST $LOCATION R1543
J 0
(-2450 2650);
DISPLAY 0.510638 (-2450 2650);
PAINT SKYBLUE (-2450 2650);
FORCEPROP 0 LAST CDS_LOCATION R1543
J 0
(-2450 2675);
DISPLAY 0.680851 (-2450 2675);
DISPLAY INVISIBLE (-2450 2675);
FORCEPROP 0 LAST $SEC 1
J 0
(-2450 2675);
DISPLAY 0.680851 (-2450 2675);
PAINT MONO (-2450 2675);
DISPLAY INVISIBLE (-2450 2675);
FORCEPROP 0 LAST CDS_SEC 1
J 0
(-2450 2675);
DISPLAY 0.680851 (-2450 2675);
DISPLAY INVISIBLE (-2450 2675);
FORCEPROP 1 LASTPIN (-2650 2650) $PN 1
J 0
(-2638 2662);
DISPLAY 0.787234 (-2638 2662);
PAINT MONO (-2638 2662);
FORCEPROP 1 LASTPIN (-2450 2650) $PN 2
J 0
(-2488 2662);
DISPLAY 0.787234 (-2488 2662);
PAINT MONO (-2488 2662);
FORCEPROP 1 LAST VALUE 0
J 2
(-2675 2650);
DISPLAY 0.489362 (-2675 2650);
PAINT SKYBLUE (-2675 2650);
FORCEPROP 2 LAST ROOM RST_CPU0_PLD_TO_DIMM
J 2
(-2525 2750);
DISPLAY 0.744681 (-2525 2750);
PAINT RED (-2525 2750);
DISPLAY INVISIBLE (-2525 2750);
FORCEPROP 1 LAST PACK_TYPE 0402LF
J 2
(-2375 2575);
DISPLAY 0.489362 (-2375 2575);
PAINT SKYBLUE (-2375 2575);
DISPLAY INVISIBLE (-2375 2575);
FORCEPROP 1 LAST PART_NUMBER CS00002JB38
J 2
(-2450 2700);
DISPLAY 0.489362 (-2450 2700);
PAINT SKYBLUE (-2450 2700);
DISPLAY INVISIBLE (-2450 2700);
FORCEPROP 1 LAST TOLERANCE 5%
J 0
(-2675 2625);
DISPLAY 0.489362 (-2675 2625);
PAINT SKYBLUE (-2675 2625);
DISPLAY INVISIBLE (-2675 2625);
FORCEPROP 1 LAST MATERIAL CHIP
J 2
(-2375 2625);
DISPLAY 0.489362 (-2375 2625);
PAINT SKYBLUE (-2375 2625);
DISPLAY INVISIBLE (-2375 2625);
FORCEPROP 1 LAST WATTAGE 1/16W
J 2
(-2625 2575);
DISPLAY 0.489362 (-2625 2575);
PAINT SKYBLUE (-2625 2575);
DISPLAY INVISIBLE (-2625 2575);
FORCEPROP 2 LAST BOM_COST MEM
J 2
(-2525 2800);
DISPLAY 0.744681 (-2525 2800);
PAINT WHITE (-2525 2800);
DISPLAY INVISIBLE (-2525 2800);
FORCEPROP 1 LAST PATH I2164
J 0
(-2600 2800);
DISPLAY 0.978723 (-2600 2800);
PAINT WHITE (-2600 2800);
DISPLAY INVISIBLE (-2600 2800);
FORCEPROP 2 LAST CDS_LIB pure_quanta
J 0
(-2550 2650);
DISPLAY INVISIBLE (-2550 2650);
FORCEADD OFFPAGE..1
R 2
(-1375 2650);
FORCEPROP 2 LAST $XR1 115 
J 0
(-1099 2650);
DISPLAY 0.638298 (-1099 2650);
PAINT MONO (-1099 2650);
FORCEPROP 2 LAST $XR0 82 
J 0
(-1189 2650);
DISPLAY 0.638298 (-1189 2650);
PAINT MONO (-1189 2650);
FORCEPROP 1 LAST OFFPAGE TRUE
J 2
(-1700 2525);
DISPLAY 0.872340 (-1700 2525);
PAINT GREEN (-1700 2525);
DISPLAY INVISIBLE (-1700 2525);
FORCEPROP 1 LAST COMMENT_BODY TRUE
J 2
(-1500 2550);
DISPLAY 0.872340 (-1500 2550);
PAINT GREEN (-1500 2550);
DISPLAY INVISIBLE (-1500 2550);
FORCEPROP 2 LAST PATH I2165
J 0
(-1200 2725);
DISPLAY 0.680851 (-1200 2725);
DISPLAY INVISIBLE (-1200 2725);
FORCEPROP 2 LAST CDS_LIB standard
J 0
(-1375 2650);
DISPLAY INVISIBLE (-1375 2650);
FORCEADD OFFPAGE..4
(-2225 4800);
FORCEPROP 2 LAST $XR1 27 
J 0
(-1919 4800);
DISPLAY 0.638298 (-1919 4800);
PAINT MONO (-1919 4800);
FORCEPROP 2 LAST $XR0 144 
J 0
(-2039 4800);
DISPLAY 0.638298 (-2039 4800);
PAINT MONO (-2039 4800);
FORCEPROP 2 LAST PATH I2182
J 0
(-1900 4850);
DISPLAY 0.680851 (-1900 4850);
DISPLAY INVISIBLE (-1900 4850);
FORCEPROP 1 LAST COMMENT_BODY TRUE
J 0
(-2250 4700);
DISPLAY 0.872340 (-2250 4700);
PAINT GREEN (-2250 4700);
DISPLAY INVISIBLE (-2250 4700);
FORCEPROP 1 LAST OFFPAGE TRUE
J 0
(-1900 4675);
DISPLAY 0.872340 (-1900 4675);
PAINT GREEN (-1900 4675);
DISPLAY INVISIBLE (-1900 4675);
FORCEPROP 2 LAST CDS_LIB standard
J 0
(-2225 4800);
DISPLAY INVISIBLE (-2225 4800);
FORCEADD OFFPAGE..1
R 2
(-2225 4850);
FORCEPROP 2 LAST $XR0 34 
J 0
(-2039 4850);
DISPLAY 0.638298 (-2039 4850);
PAINT MONO (-2039 4850);
FORCEPROP 2 LAST PATH I2183
J 0
(-2025 4900);
DISPLAY 0.680851 (-2025 4900);
DISPLAY INVISIBLE (-2025 4900);
FORCEPROP 1 LAST COMMENT_BODY TRUE
J 2
(-2350 4750);
DISPLAY 0.872340 (-2350 4750);
PAINT GREEN (-2350 4750);
DISPLAY INVISIBLE (-2350 4750);
FORCEPROP 1 LAST OFFPAGE TRUE
J 2
(-2550 4725);
DISPLAY 0.872340 (-2550 4725);
PAINT GREEN (-2550 4725);
DISPLAY INVISIBLE (-2550 4725);
FORCEPROP 2 LAST CDS_LIB standard
J 0
(-2225 4850);
DISPLAY INVISIBLE (-2225 4850);
FORCEADD Q_RES..1
(-3150 4850);
FORCEPROP 1 LAST LOCATION R937
J 0
(-3025 4850);
DISPLAY 0.489362 (-3025 4850);
PAINT SKYBLUE (-3025 4850);
FORCEPROP 0 LAST $SEC 1
J 0
(-3200 4950);
DISPLAY 0.680851 (-3200 4950);
PAINT MONO (-3200 4950);
DISPLAY INVISIBLE (-3200 4950);
FORCEPROP 0 LAST CDS_SEC 1
J 0
(-3200 4950);
DISPLAY 0.680851 (-3200 4950);
DISPLAY INVISIBLE (-3200 4950);
FORCEPROP 1 LASTPIN (-3250 4850) $PN 1
J 0
(-3238 4862);
DISPLAY 0.489362 (-3238 4862);
PAINT MONO (-3238 4862);
FORCEPROP 1 LASTPIN (-3050 4850) $PN 2
J 0
(-3088 4862);
DISPLAY 0.489362 (-3088 4862);
PAINT MONO (-3088 4862);
FORCEPROP 1 LAST VALUE 0
J 2
(-3275 4850);
DISPLAY 0.489362 (-3275 4850);
PAINT SKYBLUE (-3275 4850);
FORCEPROP 1 LAST PATH I2184
J 0
(-3200 5000);
DISPLAY 0.978723 (-3200 5000);
PAINT WHITE (-3200 5000);
DISPLAY INVISIBLE (-3200 5000);
FORCEPROP 2 LAST ROOM RST_CPU0_PLD_TO_DIMM
J 2
(-3125 4950);
DISPLAY 0.744681 (-3125 4950);
PAINT RED (-3125 4950);
DISPLAY INVISIBLE (-3125 4950);
FORCEPROP 1 LAST PACK_TYPE 0402LF
J 2
(-2975 4775);
DISPLAY 0.489362 (-2975 4775);
PAINT SKYBLUE (-2975 4775);
DISPLAY INVISIBLE (-2975 4775);
FORCEPROP 1 LAST PART_NUMBER CS00002JB38
J 2
(-3050 4900);
DISPLAY 0.489362 (-3050 4900);
PAINT SKYBLUE (-3050 4900);
DISPLAY INVISIBLE (-3050 4900);
FORCEPROP 1 LAST TOLERANCE 5%
J 0
(-3275 4825);
DISPLAY 0.489362 (-3275 4825);
PAINT SKYBLUE (-3275 4825);
DISPLAY INVISIBLE (-3275 4825);
FORCEPROP 1 LAST MATERIAL CHIP
J 2
(-2975 4825);
DISPLAY 0.489362 (-2975 4825);
PAINT SKYBLUE (-2975 4825);
DISPLAY INVISIBLE (-2975 4825);
FORCEPROP 1 LAST WATTAGE 1/16W
J 2
(-3225 4775);
DISPLAY 0.489362 (-3225 4775);
PAINT SKYBLUE (-3225 4775);
DISPLAY INVISIBLE (-3225 4775);
FORCEPROP 2 LAST BOM_COST MEM
J 2
(-3125 5000);
DISPLAY 0.744681 (-3125 5000);
PAINT WHITE (-3125 5000);
DISPLAY INVISIBLE (-3125 5000);
FORCEPROP 2 LAST CDS_LIB pure_quanta
J 0
(-3150 4850);
DISPLAY INVISIBLE (-3150 4850);
FORCEADD OFFPAGE..2
(-2225 4900);
FORCEPROP 2 LAST $XR0 149 
J 0
(-2036 4900);
DISPLAY 0.638298 (-2036 4900);
PAINT MONO (-2036 4900);
FORCEPROP 2 LAST PATH I2185
J 0
(-2025 4950);
DISPLAY 0.680851 (-2025 4950);
DISPLAY INVISIBLE (-2025 4950);
FORCEPROP 1 LAST COMMENT_BODY TRUE
J 0
(-2270 4805);
DISPLAY 0.872340 (-2270 4805);
PAINT GREEN (-2270 4805);
DISPLAY INVISIBLE (-2270 4805);
FORCEPROP 1 LAST OFFPAGE TRUE
J 0
(-1900 4775);
DISPLAY 0.872340 (-1900 4775);
PAINT GREEN (-1900 4775);
DISPLAY INVISIBLE (-1900 4775);
FORCEPROP 2 LAST CDS_LIB standard
J 0
(-2225 4900);
DISPLAY INVISIBLE (-2225 4900);
FORCEADD Q_RES..1
(-3150 4900);
FORCEPROP 1 LAST LOCATION R856
J 0
(-3025 4900);
DISPLAY 0.489362 (-3025 4900);
PAINT SKYBLUE (-3025 4900);
FORCEPROP 0 LAST $SEC 1
J 0
(-3025 4950);
DISPLAY 0.680851 (-3025 4950);
PAINT MONO (-3025 4950);
DISPLAY INVISIBLE (-3025 4950);
FORCEPROP 0 LAST CDS_SEC 1
J 0
(-3025 4950);
DISPLAY 0.680851 (-3025 4950);
DISPLAY INVISIBLE (-3025 4950);
FORCEPROP 1 LASTPIN (-3250 4900) $PN 1
J 0
(-3238 4912);
DISPLAY 0.489362 (-3238 4912);
PAINT MONO (-3238 4912);
FORCEPROP 1 LASTPIN (-3050 4900) $PN 2
J 0
(-3088 4912);
DISPLAY 0.489362 (-3088 4912);
PAINT MONO (-3088 4912);
FORCEPROP 1 LAST VALUE 0
J 2
(-3275 4900);
DISPLAY 0.489362 (-3275 4900);
PAINT SKYBLUE (-3275 4900);
FORCEPROP 1 LAST PATH I2186
J 0
(-3200 5050);
DISPLAY 0.978723 (-3200 5050);
PAINT WHITE (-3200 5050);
DISPLAY INVISIBLE (-3200 5050);
FORCEPROP 2 LAST ROOM RST_CPU0_PLD_TO_DIMM
J 2
(-3125 5000);
DISPLAY 0.744681 (-3125 5000);
PAINT RED (-3125 5000);
DISPLAY INVISIBLE (-3125 5000);
FORCEPROP 1 LAST PACK_TYPE 0402LF
J 2
(-2975 4825);
DISPLAY 0.489362 (-2975 4825);
PAINT SKYBLUE (-2975 4825);
DISPLAY INVISIBLE (-2975 4825);
FORCEPROP 1 LAST PART_NUMBER CS00002JB38
J 2
(-3050 4950);
DISPLAY 0.489362 (-3050 4950);
PAINT SKYBLUE (-3050 4950);
DISPLAY INVISIBLE (-3050 4950);
FORCEPROP 1 LAST TOLERANCE 5%
J 0
(-3275 4875);
DISPLAY 0.489362 (-3275 4875);
PAINT SKYBLUE (-3275 4875);
DISPLAY INVISIBLE (-3275 4875);
FORCEPROP 1 LAST MATERIAL CHIP
J 2
(-2975 4875);
DISPLAY 0.489362 (-2975 4875);
PAINT SKYBLUE (-2975 4875);
DISPLAY INVISIBLE (-2975 4875);
FORCEPROP 1 LAST WATTAGE 1/16W
J 2
(-3225 4825);
DISPLAY 0.489362 (-3225 4825);
PAINT SKYBLUE (-3225 4825);
DISPLAY INVISIBLE (-3225 4825);
FORCEPROP 2 LAST BOM_COST MEM
J 2
(-3125 5050);
DISPLAY 0.744681 (-3125 5050);
PAINT WHITE (-3125 5050);
DISPLAY INVISIBLE (-3125 5050);
FORCEPROP 2 LAST CDS_LIB pure_quanta
J 0
(-3150 4900);
DISPLAY INVISIBLE (-3150 4900);
FORCEADD OFFPAGE..2
(-2225 4950);
FORCEPROP 2 LAST $XR0 149 
J 0
(-2036 4950);
DISPLAY 0.638298 (-2036 4950);
PAINT MONO (-2036 4950);
FORCEPROP 2 LAST PATH I2187
J 0
(-2025 5000);
DISPLAY 0.680851 (-2025 5000);
DISPLAY INVISIBLE (-2025 5000);
FORCEPROP 1 LAST COMMENT_BODY TRUE
J 0
(-2270 4855);
DISPLAY 0.872340 (-2270 4855);
PAINT GREEN (-2270 4855);
DISPLAY INVISIBLE (-2270 4855);
FORCEPROP 1 LAST OFFPAGE TRUE
J 0
(-1900 4825);
DISPLAY 0.872340 (-1900 4825);
PAINT GREEN (-1900 4825);
DISPLAY INVISIBLE (-1900 4825);
FORCEPROP 2 LAST CDS_LIB standard
J 0
(-2225 4950);
DISPLAY INVISIBLE (-2225 4950);
FORCEADD Q_RES..1
(-3150 4950);
FORCEPROP 1 LAST LOCATION R708
J 0
(-3025 4950);
DISPLAY 0.489362 (-3025 4950);
PAINT SKYBLUE (-3025 4950);
FORCEPROP 0 LAST $SEC 1
J 0
(-3025 5000);
DISPLAY 0.680851 (-3025 5000);
PAINT MONO (-3025 5000);
DISPLAY INVISIBLE (-3025 5000);
FORCEPROP 0 LAST CDS_SEC 1
J 0
(-3025 5000);
DISPLAY 0.680851 (-3025 5000);
DISPLAY INVISIBLE (-3025 5000);
FORCEPROP 1 LASTPIN (-3250 4950) $PN 1
J 0
(-3238 4962);
DISPLAY 0.489362 (-3238 4962);
PAINT MONO (-3238 4962);
FORCEPROP 1 LASTPIN (-3050 4950) $PN 2
J 0
(-3088 4962);
DISPLAY 0.489362 (-3088 4962);
PAINT MONO (-3088 4962);
FORCEPROP 1 LAST VALUE 33
J 2
(-3275 4950);
DISPLAY 0.489362 (-3275 4950);
PAINT SKYBLUE (-3275 4950);
FORCEPROP 1 LAST PATH I2188
J 0
(-3200 5100);
DISPLAY 0.978723 (-3200 5100);
PAINT WHITE (-3200 5100);
DISPLAY INVISIBLE (-3200 5100);
FORCEPROP 2 LAST ROOM RST_CPU0_PLD_TO_DIMM
J 2
(-3125 5050);
DISPLAY 0.744681 (-3125 5050);
PAINT RED (-3125 5050);
DISPLAY INVISIBLE (-3125 5050);
FORCEPROP 1 LAST PACK_TYPE 0402LF
J 2
(-2975 4875);
DISPLAY 0.489362 (-2975 4875);
PAINT SKYBLUE (-2975 4875);
DISPLAY INVISIBLE (-2975 4875);
FORCEPROP 1 LAST PART_NUMBER CS03302JB29
J 2
(-3050 5000);
DISPLAY 0.489362 (-3050 5000);
PAINT SKYBLUE (-3050 5000);
DISPLAY INVISIBLE (-3050 5000);
FORCEPROP 1 LAST TOLERANCE 5%
J 0
(-3275 4925);
DISPLAY 0.489362 (-3275 4925);
PAINT SKYBLUE (-3275 4925);
DISPLAY INVISIBLE (-3275 4925);
FORCEPROP 1 LAST MATERIAL CHIP
J 2
(-2975 4925);
DISPLAY 0.489362 (-2975 4925);
PAINT SKYBLUE (-2975 4925);
DISPLAY INVISIBLE (-2975 4925);
FORCEPROP 1 LAST WATTAGE 1/16W
J 2
(-3225 4875);
DISPLAY 0.489362 (-3225 4875);
PAINT SKYBLUE (-3225 4875);
DISPLAY INVISIBLE (-3225 4875);
FORCEPROP 2 LAST BOM_COST MEM
J 2
(-3125 5100);
DISPLAY 0.744681 (-3125 5100);
PAINT WHITE (-3125 5100);
DISPLAY INVISIBLE (-3125 5100);
FORCEPROP 2 LAST CDS_LIB pure_quanta
J 0
(-3150 4950);
DISPLAY INVISIBLE (-3150 4950);
FORCEADD OFFPAGE..6
R 2
(-2225 5150);
FORCEPROP 2 LAST $XR1 117 
J 0
(-1921 5150);
DISPLAY 0.638298 (-1921 5150);
PAINT MONO (-1921 5150);
FORCEPROP 2 LAST $XR0 29 
J 0
(-2011 5150);
DISPLAY 0.638298 (-2011 5150);
PAINT MONO (-2011 5150);
FORCEPROP 2 LAST PATH I2189
J 0
(-1900 5200);
DISPLAY 0.680851 (-1900 5200);
DISPLAY INVISIBLE (-1900 5200);
FORCEPROP 2 LAST CDS_LIB standard
J 0
(-2225 5150);
DISPLAY INVISIBLE (-2225 5150);
FORCEPROP 1 LAST OFFPAGE TRUE
J 2
(-2550 5025);
DISPLAY 0.872340 (-2550 5025);
PAINT GREEN (-2550 5025);
DISPLAY INVISIBLE (-2550 5025);
FORCEPROP 1 LAST COMMENT_BODY TRUE
J 2
(-2325 5075);
DISPLAY 0.872340 (-2325 5075);
PAINT GREEN (-2325 5075);
DISPLAY INVISIBLE (-2325 5075);
FORCEADD OFFPAGE..6
R 2
(-2225 5100);
FORCEPROP 2 LAST $XR1 117 
J 0
(-1921 5100);
DISPLAY 0.638298 (-1921 5100);
PAINT MONO (-1921 5100);
FORCEPROP 2 LAST $XR0 29 
J 0
(-2011 5100);
DISPLAY 0.638298 (-2011 5100);
PAINT MONO (-2011 5100);
FORCEPROP 2 LAST PATH I2190
J 0
(-1900 5150);
DISPLAY 0.680851 (-1900 5150);
DISPLAY INVISIBLE (-1900 5150);
FORCEPROP 2 LAST CDS_LIB standard
J 0
(-2225 5100);
DISPLAY INVISIBLE (-2225 5100);
FORCEPROP 1 LAST OFFPAGE TRUE
J 2
(-2550 4975);
DISPLAY 0.872340 (-2550 4975);
PAINT GREEN (-2550 4975);
DISPLAY INVISIBLE (-2550 4975);
FORCEPROP 1 LAST COMMENT_BODY TRUE
J 2
(-2325 5025);
DISPLAY 0.872340 (-2325 5025);
PAINT GREEN (-2325 5025);
DISPLAY INVISIBLE (-2325 5025);
FORCEADD OFFPAGE..6
R 2
(-2225 5050);
FORCEPROP 2 LAST $XR1 117 
J 0
(-1921 5050);
DISPLAY 0.638298 (-1921 5050);
PAINT MONO (-1921 5050);
FORCEPROP 2 LAST $XR0 29 
J 0
(-2011 5050);
DISPLAY 0.638298 (-2011 5050);
PAINT MONO (-2011 5050);
FORCEPROP 2 LAST PATH I2191
J 0
(-1900 5100);
DISPLAY 0.680851 (-1900 5100);
DISPLAY INVISIBLE (-1900 5100);
FORCEPROP 2 LAST CDS_LIB standard
J 0
(-2225 5050);
DISPLAY INVISIBLE (-2225 5050);
FORCEPROP 1 LAST OFFPAGE TRUE
J 2
(-2550 4925);
DISPLAY 0.872340 (-2550 4925);
PAINT GREEN (-2550 4925);
DISPLAY INVISIBLE (-2550 4925);
FORCEPROP 1 LAST COMMENT_BODY TRUE
J 2
(-2325 4975);
DISPLAY 0.872340 (-2325 4975);
PAINT GREEN (-2325 4975);
DISPLAY INVISIBLE (-2325 4975);
FORCEADD OFFPAGE..6
R 2
(-2225 5000);
FORCEPROP 2 LAST $XR1 117 
J 0
(-1921 5000);
DISPLAY 0.638298 (-1921 5000);
PAINT MONO (-1921 5000);
FORCEPROP 2 LAST $XR0 29 
J 0
(-2011 5000);
DISPLAY 0.638298 (-2011 5000);
PAINT MONO (-2011 5000);
FORCEPROP 2 LAST PATH I2192
J 0
(-1900 5050);
DISPLAY 0.680851 (-1900 5050);
DISPLAY INVISIBLE (-1900 5050);
FORCEPROP 1 LAST COMMENT_BODY TRUE
J 2
(-2325 4925);
DISPLAY 0.872340 (-2325 4925);
PAINT GREEN (-2325 4925);
DISPLAY INVISIBLE (-2325 4925);
FORCEPROP 1 LAST OFFPAGE TRUE
J 2
(-2550 4875);
DISPLAY 0.872340 (-2550 4875);
PAINT GREEN (-2550 4875);
DISPLAY INVISIBLE (-2550 4875);
FORCEPROP 2 LAST CDS_LIB standard
J 0
(-2225 5000);
DISPLAY INVISIBLE (-2225 5000);
FORCEADD Q_RES..1
(-3150 5150);
FORCEPROP 1 LAST $LOCATION R1549
J 0
(-3025 5150);
DISPLAY 0.489362 (-3025 5150);
PAINT SKYBLUE (-3025 5150);
FORCEPROP 0 LAST CDS_LOCATION R1549
J 0
(-3025 5175);
DISPLAY 0.680851 (-3025 5175);
DISPLAY INVISIBLE (-3025 5175);
FORCEPROP 0 LAST $SEC 1
J 0
(-3025 5175);
DISPLAY 0.680851 (-3025 5175);
PAINT MONO (-3025 5175);
DISPLAY INVISIBLE (-3025 5175);
FORCEPROP 0 LAST CDS_SEC 1
J 0
(-3025 5175);
DISPLAY 0.680851 (-3025 5175);
DISPLAY INVISIBLE (-3025 5175);
FORCEPROP 1 LASTPIN (-3250 5150) $PN 1
J 0
(-3238 5162);
DISPLAY 0.404255 (-3238 5162);
PAINT MONO (-3238 5162);
FORCEPROP 1 LASTPIN (-3050 5150) $PN 2
J 0
(-3088 5162);
DISPLAY 0.510638 (-3088 5162);
PAINT MONO (-3088 5162);
FORCEPROP 1 LAST VALUE 33
J 2
(-3275 5150);
DISPLAY 0.489362 (-3275 5150);
PAINT SKYBLUE (-3275 5150);
FORCEPROP 1 LAST PATH I2193
J 0
(-3200 5300);
DISPLAY 0.978723 (-3200 5300);
PAINT WHITE (-3200 5300);
DISPLAY INVISIBLE (-3200 5300);
FORCEPROP 2 LAST CDS_LIB pure_quanta
J 0
(-3150 5150);
DISPLAY INVISIBLE (-3150 5150);
FORCEPROP 2 LAST BOM_COST MEM
J 2
(-3125 5300);
DISPLAY 0.744681 (-3125 5300);
PAINT WHITE (-3125 5300);
DISPLAY INVISIBLE (-3125 5300);
FORCEPROP 1 LAST WATTAGE 1/16W
J 2
(-3225 5075);
DISPLAY 0.489362 (-3225 5075);
PAINT SKYBLUE (-3225 5075);
DISPLAY INVISIBLE (-3225 5075);
FORCEPROP 1 LAST MATERIAL CHIP
J 2
(-2975 5125);
DISPLAY 0.489362 (-2975 5125);
PAINT SKYBLUE (-2975 5125);
DISPLAY INVISIBLE (-2975 5125);
FORCEPROP 1 LAST TOLERANCE 5%
J 0
(-3275 5125);
DISPLAY 0.489362 (-3275 5125);
PAINT SKYBLUE (-3275 5125);
DISPLAY INVISIBLE (-3275 5125);
FORCEPROP 1 LAST PART_NUMBER CS03302JB29
J 2
(-3050 5200);
DISPLAY 0.489362 (-3050 5200);
PAINT SKYBLUE (-3050 5200);
DISPLAY INVISIBLE (-3050 5200);
FORCEPROP 1 LAST PACK_TYPE 0402LF
J 2
(-2975 5075);
DISPLAY 0.489362 (-2975 5075);
PAINT SKYBLUE (-2975 5075);
DISPLAY INVISIBLE (-2975 5075);
FORCEPROP 2 LAST ROOM RST_CPU0_PLD_TO_DIMM
J 2
(-3125 5250);
DISPLAY 0.744681 (-3125 5250);
PAINT RED (-3125 5250);
DISPLAY INVISIBLE (-3125 5250);
FORCEADD Q_RES..1
(-3150 5100);
FORCEPROP 1 LAST $LOCATION R1550
J 0
(-3025 5100);
DISPLAY 0.510638 (-3025 5100);
PAINT SKYBLUE (-3025 5100);
FORCEPROP 0 LAST CDS_LOCATION R1550
J 0
(-3025 5125);
DISPLAY 0.680851 (-3025 5125);
DISPLAY INVISIBLE (-3025 5125);
FORCEPROP 0 LAST $SEC 1
J 0
(-3025 5125);
DISPLAY 0.680851 (-3025 5125);
PAINT MONO (-3025 5125);
DISPLAY INVISIBLE (-3025 5125);
FORCEPROP 0 LAST CDS_SEC 1
J 0
(-3025 5125);
DISPLAY 0.680851 (-3025 5125);
DISPLAY INVISIBLE (-3025 5125);
FORCEPROP 1 LASTPIN (-3250 5100) $PN 1
J 0
(-3238 5112);
DISPLAY 0.510638 (-3238 5112);
PAINT MONO (-3238 5112);
FORCEPROP 1 LASTPIN (-3050 5100) $PN 2
J 0
(-3088 5112);
DISPLAY 0.510638 (-3088 5112);
PAINT MONO (-3088 5112);
FORCEPROP 1 LAST VALUE 33
J 2
(-3275 5100);
DISPLAY 0.489362 (-3275 5100);
PAINT SKYBLUE (-3275 5100);
FORCEPROP 1 LAST PATH I2194
J 0
(-3200 5250);
DISPLAY 0.978723 (-3200 5250);
PAINT WHITE (-3200 5250);
DISPLAY INVISIBLE (-3200 5250);
FORCEPROP 2 LAST ROOM RST_CPU0_PLD_TO_DIMM
J 2
(-3125 5200);
DISPLAY 0.744681 (-3125 5200);
PAINT RED (-3125 5200);
DISPLAY INVISIBLE (-3125 5200);
FORCEPROP 1 LAST PACK_TYPE 0402LF
J 2
(-2975 5025);
DISPLAY 0.489362 (-2975 5025);
PAINT SKYBLUE (-2975 5025);
DISPLAY INVISIBLE (-2975 5025);
FORCEPROP 1 LAST PART_NUMBER CS03302JB29
J 2
(-3050 5150);
DISPLAY 0.489362 (-3050 5150);
PAINT SKYBLUE (-3050 5150);
DISPLAY INVISIBLE (-3050 5150);
FORCEPROP 1 LAST TOLERANCE 5%
J 0
(-3275 5075);
DISPLAY 0.489362 (-3275 5075);
PAINT SKYBLUE (-3275 5075);
DISPLAY INVISIBLE (-3275 5075);
FORCEPROP 1 LAST MATERIAL CHIP
J 2
(-2975 5075);
DISPLAY 0.489362 (-2975 5075);
PAINT SKYBLUE (-2975 5075);
DISPLAY INVISIBLE (-2975 5075);
FORCEPROP 1 LAST WATTAGE 1/16W
J 2
(-3225 5025);
DISPLAY 0.489362 (-3225 5025);
PAINT SKYBLUE (-3225 5025);
DISPLAY INVISIBLE (-3225 5025);
FORCEPROP 2 LAST BOM_COST MEM
J 2
(-3125 5250);
DISPLAY 0.744681 (-3125 5250);
PAINT WHITE (-3125 5250);
DISPLAY INVISIBLE (-3125 5250);
FORCEPROP 2 LAST CDS_LIB pure_quanta
J 0
(-3150 5100);
DISPLAY INVISIBLE (-3150 5100);
FORCEADD Q_RES..1
(-3150 5050);
FORCEPROP 1 LAST $LOCATION R1551
J 0
(-3025 5050);
DISPLAY 0.489362 (-3025 5050);
PAINT SKYBLUE (-3025 5050);
FORCEPROP 0 LAST CDS_LOCATION R1551
J 0
(-3025 5075);
DISPLAY 0.680851 (-3025 5075);
DISPLAY INVISIBLE (-3025 5075);
FORCEPROP 0 LAST $SEC 1
J 0
(-3025 5075);
DISPLAY 0.680851 (-3025 5075);
PAINT MONO (-3025 5075);
DISPLAY INVISIBLE (-3025 5075);
FORCEPROP 0 LAST CDS_SEC 1
J 0
(-3025 5075);
DISPLAY 0.680851 (-3025 5075);
DISPLAY INVISIBLE (-3025 5075);
FORCEPROP 1 LASTPIN (-3250 5050) $PN 1
J 0
(-3238 5062);
DISPLAY 0.510638 (-3238 5062);
PAINT MONO (-3238 5062);
FORCEPROP 1 LASTPIN (-3050 5050) $PN 2
J 0
(-3088 5062);
DISPLAY 0.510638 (-3088 5062);
PAINT MONO (-3088 5062);
FORCEPROP 1 LAST VALUE 33
J 2
(-3275 5050);
DISPLAY 0.489362 (-3275 5050);
PAINT SKYBLUE (-3275 5050);
FORCEPROP 1 LAST PATH I2195
J 0
(-3200 5200);
DISPLAY 0.978723 (-3200 5200);
PAINT WHITE (-3200 5200);
DISPLAY INVISIBLE (-3200 5200);
FORCEPROP 2 LAST ROOM RST_CPU0_PLD_TO_DIMM
J 2
(-3125 5150);
DISPLAY 0.744681 (-3125 5150);
PAINT RED (-3125 5150);
DISPLAY INVISIBLE (-3125 5150);
FORCEPROP 1 LAST PACK_TYPE 0402LF
J 2
(-2975 4975);
DISPLAY 0.489362 (-2975 4975);
PAINT SKYBLUE (-2975 4975);
DISPLAY INVISIBLE (-2975 4975);
FORCEPROP 1 LAST PART_NUMBER CS03302JB29
J 2
(-3050 5100);
DISPLAY 0.489362 (-3050 5100);
PAINT SKYBLUE (-3050 5100);
DISPLAY INVISIBLE (-3050 5100);
FORCEPROP 1 LAST TOLERANCE 5%
J 0
(-3275 5025);
DISPLAY 0.489362 (-3275 5025);
PAINT SKYBLUE (-3275 5025);
DISPLAY INVISIBLE (-3275 5025);
FORCEPROP 1 LAST MATERIAL CHIP
J 2
(-2975 5025);
DISPLAY 0.489362 (-2975 5025);
PAINT SKYBLUE (-2975 5025);
DISPLAY INVISIBLE (-2975 5025);
FORCEPROP 1 LAST WATTAGE 1/16W
J 2
(-3225 4975);
DISPLAY 0.489362 (-3225 4975);
PAINT SKYBLUE (-3225 4975);
DISPLAY INVISIBLE (-3225 4975);
FORCEPROP 2 LAST BOM_COST MEM
J 2
(-3125 5200);
DISPLAY 0.744681 (-3125 5200);
PAINT WHITE (-3125 5200);
DISPLAY INVISIBLE (-3125 5200);
FORCEPROP 2 LAST CDS_LIB pure_quanta
J 0
(-3150 5050);
DISPLAY INVISIBLE (-3150 5050);
FORCEADD Q_RES..1
(-3150 5000);
FORCEPROP 1 LAST $LOCATION R1552
J 0
(-3025 5000);
DISPLAY 0.489362 (-3025 5000);
PAINT SKYBLUE (-3025 5000);
FORCEPROP 0 LAST CDS_LOCATION R1552
J 0
(-3025 5025);
DISPLAY 0.680851 (-3025 5025);
DISPLAY INVISIBLE (-3025 5025);
FORCEPROP 0 LAST $SEC 1
J 0
(-3025 5025);
DISPLAY 0.680851 (-3025 5025);
PAINT MONO (-3025 5025);
DISPLAY INVISIBLE (-3025 5025);
FORCEPROP 0 LAST CDS_SEC 1
J 0
(-3025 5025);
DISPLAY 0.680851 (-3025 5025);
DISPLAY INVISIBLE (-3025 5025);
FORCEPROP 1 LASTPIN (-3250 5000) $PN 1
J 0
(-3238 5012);
DISPLAY 0.510638 (-3238 5012);
PAINT MONO (-3238 5012);
FORCEPROP 1 LASTPIN (-3050 5000) $PN 2
J 0
(-3088 5012);
DISPLAY 0.510638 (-3088 5012);
PAINT MONO (-3088 5012);
FORCEPROP 1 LAST VALUE 33
J 2
(-3275 5000);
DISPLAY 0.489362 (-3275 5000);
PAINT SKYBLUE (-3275 5000);
FORCEPROP 1 LAST PATH I2196
J 0
(-3200 5150);
DISPLAY 0.978723 (-3200 5150);
PAINT WHITE (-3200 5150);
DISPLAY INVISIBLE (-3200 5150);
FORCEPROP 2 LAST ROOM RST_CPU0_PLD_TO_DIMM
J 2
(-3125 5100);
DISPLAY 0.744681 (-3125 5100);
PAINT RED (-3125 5100);
DISPLAY INVISIBLE (-3125 5100);
FORCEPROP 1 LAST PACK_TYPE 0402LF
J 2
(-2975 4925);
DISPLAY 0.489362 (-2975 4925);
PAINT SKYBLUE (-2975 4925);
DISPLAY INVISIBLE (-2975 4925);
FORCEPROP 1 LAST PART_NUMBER CS03302JB29
J 2
(-3050 5050);
DISPLAY 0.489362 (-3050 5050);
PAINT SKYBLUE (-3050 5050);
DISPLAY INVISIBLE (-3050 5050);
FORCEPROP 1 LAST TOLERANCE 5%
J 0
(-3275 4975);
DISPLAY 0.489362 (-3275 4975);
PAINT SKYBLUE (-3275 4975);
DISPLAY INVISIBLE (-3275 4975);
FORCEPROP 1 LAST MATERIAL CHIP
J 2
(-2975 4975);
DISPLAY 0.489362 (-2975 4975);
PAINT SKYBLUE (-2975 4975);
DISPLAY INVISIBLE (-2975 4975);
FORCEPROP 1 LAST WATTAGE 1/16W
J 2
(-3225 4925);
DISPLAY 0.489362 (-3225 4925);
PAINT SKYBLUE (-3225 4925);
DISPLAY INVISIBLE (-3225 4925);
FORCEPROP 2 LAST BOM_COST MEM
J 2
(-3125 5150);
DISPLAY 0.744681 (-3125 5150);
PAINT WHITE (-3125 5150);
DISPLAY INVISIBLE (-3125 5150);
FORCEPROP 2 LAST CDS_LIB pure_quanta
J 0
(-3150 5000);
DISPLAY INVISIBLE (-3150 5000);
FORCEADD Q_RES..1
(-3150 5300);
FORCEPROP 1 LAST $LOCATION R1553
J 0
(-3025 5300);
DISPLAY 0.489362 (-3025 5300);
PAINT SKYBLUE (-3025 5300);
FORCEPROP 0 LAST CDS_LOCATION R1553
J 0
(-3025 5325);
DISPLAY 0.680851 (-3025 5325);
DISPLAY INVISIBLE (-3025 5325);
FORCEPROP 0 LAST $SEC 1
J 0
(-3025 5325);
DISPLAY 0.680851 (-3025 5325);
PAINT MONO (-3025 5325);
DISPLAY INVISIBLE (-3025 5325);
FORCEPROP 0 LAST CDS_SEC 1
J 0
(-3025 5325);
DISPLAY 0.680851 (-3025 5325);
DISPLAY INVISIBLE (-3025 5325);
FORCEPROP 1 LASTPIN (-3250 5300) $PN 1
J 0
(-3238 5312);
DISPLAY 0.510638 (-3238 5312);
PAINT MONO (-3238 5312);
FORCEPROP 1 LASTPIN (-3050 5300) $PN 2
J 0
(-3088 5312);
DISPLAY 0.510638 (-3088 5312);
PAINT MONO (-3088 5312);
FORCEPROP 1 LAST VALUE 33
J 2
(-3250 5300);
DISPLAY 0.489362 (-3250 5300);
PAINT SKYBLUE (-3250 5300);
FORCEPROP 2 LAST CDS_LIB pure_quanta
J 0
(-3150 5300);
DISPLAY INVISIBLE (-3150 5300);
FORCEPROP 1 LAST PATH I2199
J 0
(-3200 5450);
DISPLAY 0.978723 (-3200 5450);
PAINT WHITE (-3200 5450);
DISPLAY INVISIBLE (-3200 5450);
FORCEPROP 1 LAST PACK_TYPE 0402LF
J 0
(-3100 5225);
DISPLAY 0.489362 (-3100 5225);
PAINT SKYBLUE (-3100 5225);
DISPLAY INVISIBLE (-3100 5225);
FORCEPROP 1 LAST PART_NUMBER CS03302JB29
J 0
(-3125 5350);
DISPLAY 0.489362 (-3125 5350);
PAINT SKYBLUE (-3125 5350);
DISPLAY INVISIBLE (-3125 5350);
FORCEPROP 1 LAST TOLERANCE 5%
J 0
(-3175 5225);
DISPLAY 0.489362 (-3175 5225);
PAINT SKYBLUE (-3175 5225);
DISPLAY INVISIBLE (-3175 5225);
FORCEPROP 1 LAST MATERIAL CHIP
J 0
(-2725 5225);
DISPLAY 0.489362 (-2725 5225);
PAINT SKYBLUE (-2725 5225);
DISPLAY INVISIBLE (-2725 5225);
FORCEPROP 1 LAST WATTAGE 1/16W
J 2
(-2750 5225);
DISPLAY 0.489362 (-2750 5225);
PAINT SKYBLUE (-2750 5225);
DISPLAY INVISIBLE (-2750 5225);
FORCEADD OFFPAGE..1
R 2
(-2225 5300);
FORCEPROP 2 LAST $XR1 117 
J 0
(-1949 5300);
DISPLAY 0.638298 (-1949 5300);
PAINT MONO (-1949 5300);
FORCEPROP 2 LAST $XR0 29 
J 0
(-2039 5300);
DISPLAY 0.638298 (-2039 5300);
PAINT MONO (-2039 5300);
FORCEPROP 2 LAST CDS_LIB standard
J 0
(-2225 5300);
DISPLAY INVISIBLE (-2225 5300);
FORCEPROP 2 LAST PATH I2200
J 0
(-2050 5375);
DISPLAY 0.680851 (-2050 5375);
DISPLAY INVISIBLE (-2050 5375);
FORCEPROP 1 LAST OFFPAGE TRUE
J 2
(-2550 5175);
DISPLAY 0.872340 (-2550 5175);
PAINT GREEN (-2550 5175);
DISPLAY INVISIBLE (-2550 5175);
FORCEPROP 1 LAST COMMENT_BODY TRUE
J 2
(-2350 5200);
DISPLAY 0.872340 (-2350 5200);
PAINT GREEN (-2350 5200);
DISPLAY INVISIBLE (-2350 5200);
FORCEADD Q_RES..1
(-6350 4850);
FORCEPROP 1 LAST LOCATION R159
J 0
(-6225 4850);
DISPLAY 0.489362 (-6225 4850);
PAINT SKYBLUE (-6225 4850);
FORCEPROP 0 LAST $SEC 1
J 2
(-6225 4900);
DISPLAY 0.680851 (-6225 4900);
PAINT MONO (-6225 4900);
DISPLAY INVISIBLE (-6225 4900);
FORCEPROP 0 LAST CDS_SEC 1
J 2
(-6225 4900);
DISPLAY 1.021277 (-6225 4900);
DISPLAY INVISIBLE (-6225 4900);
FORCEPROP 1 LASTPIN (-6450 4850) $PN 1
J 0
(-6438 4862);
DISPLAY 0.489362 (-6438 4862);
PAINT MONO (-6438 4862);
FORCEPROP 1 LASTPIN (-6250 4850) $PN 2
J 0
(-6288 4862);
DISPLAY 0.489362 (-6288 4862);
PAINT MONO (-6288 4862);
FORCEPROP 1 LAST VALUE 33
J 2
(-6475 4850);
DISPLAY 0.489362 (-6475 4850);
PAINT SKYBLUE (-6475 4850);
FORCEPROP 1 LAST PATH I2201
J 0
(-6400 5000);
DISPLAY 0.978723 (-6400 5000);
PAINT WHITE (-6400 5000);
DISPLAY INVISIBLE (-6400 5000);
FORCEPROP 2 LAST ROOM RST_CPU0_PLD_TO_DIMM
J 2
(-6325 4950);
DISPLAY 0.744681 (-6325 4950);
PAINT RED (-6325 4950);
DISPLAY INVISIBLE (-6325 4950);
FORCEPROP 1 LAST PACK_TYPE 0402LF
J 2
(-6175 4775);
DISPLAY 0.489362 (-6175 4775);
PAINT SKYBLUE (-6175 4775);
DISPLAY INVISIBLE (-6175 4775);
FORCEPROP 1 LAST PART_NUMBER CS03302JB29
J 2
(-6250 4900);
DISPLAY 0.489362 (-6250 4900);
PAINT SKYBLUE (-6250 4900);
DISPLAY INVISIBLE (-6250 4900);
FORCEPROP 1 LAST TOLERANCE 5%
J 0
(-6475 4825);
DISPLAY 0.489362 (-6475 4825);
PAINT SKYBLUE (-6475 4825);
DISPLAY INVISIBLE (-6475 4825);
FORCEPROP 1 LAST MATERIAL CHIP
J 2
(-6175 4825);
DISPLAY 0.489362 (-6175 4825);
PAINT SKYBLUE (-6175 4825);
DISPLAY INVISIBLE (-6175 4825);
FORCEPROP 1 LAST WATTAGE 1/16W
J 2
(-6425 4775);
DISPLAY 0.489362 (-6425 4775);
PAINT SKYBLUE (-6425 4775);
DISPLAY INVISIBLE (-6425 4775);
FORCEPROP 2 LAST BOM_COST MEM
J 2
(-6325 5000);
DISPLAY 0.744681 (-6325 5000);
PAINT WHITE (-6325 5000);
DISPLAY INVISIBLE (-6325 5000);
FORCEPROP 2 LAST CDS_LIB pure_quanta
J 2
(-6350 4850);
DISPLAY INVISIBLE (-6350 4850);
FORCEADD OFFPAGE..2
R 2
(-7275 4850);
FORCEPROP 2 LAST $XR0 150 
J 0
(-7560 4850);
DISPLAY 0.638298 (-7560 4850);
PAINT MONO (-7560 4850);
FORCEPROP 2 LAST CDS_LIB standard
J 0
(-7275 4850);
DISPLAY INVISIBLE (-7275 4850);
FORCEPROP 2 LAST PATH I2202
J 0
(-7225 4925);
DISPLAY 0.680851 (-7225 4925);
DISPLAY INVISIBLE (-7225 4925);
FORCEPROP 1 LAST OFFPAGE TRUE
J 2
(-7600 4725);
DISPLAY 0.872340 (-7600 4725);
PAINT GREEN (-7600 4725);
DISPLAY INVISIBLE (-7600 4725);
FORCEPROP 1 LAST COMMENT_BODY TRUE
J 2
(-7230 4755);
DISPLAY 0.872340 (-7230 4755);
PAINT GREEN (-7230 4755);
DISPLAY INVISIBLE (-7230 4755);
FORCEADD Q_RES..1
(-3150 5350);
FORCEPROP 1 LAST $LOCATION R1556
J 0
(-3025 5350);
DISPLAY 0.510638 (-3025 5350);
PAINT SKYBLUE (-3025 5350);
FORCEPROP 0 LAST CDS_LOCATION R1556
J 0
(-3075 5375);
DISPLAY 0.680851 (-3075 5375);
DISPLAY INVISIBLE (-3075 5375);
FORCEPROP 0 LAST $SEC 1
J 0
(-3075 5375);
DISPLAY 0.680851 (-3075 5375);
PAINT MONO (-3075 5375);
DISPLAY INVISIBLE (-3075 5375);
FORCEPROP 0 LAST CDS_SEC 1
J 0
(-3075 5375);
DISPLAY 0.680851 (-3075 5375);
DISPLAY INVISIBLE (-3075 5375);
FORCEPROP 1 LASTPIN (-3250 5350) $PN 1
J 0
(-3238 5362);
DISPLAY 0.787234 (-3238 5362);
PAINT MONO (-3238 5362);
FORCEPROP 1 LASTPIN (-3050 5350) $PN 2
J 0
(-3088 5362);
DISPLAY 0.787234 (-3088 5362);
PAINT MONO (-3088 5362);
FORCEPROP 1 LAST VALUE 33
J 2
(-3250 5350);
DISPLAY 0.489362 (-3250 5350);
PAINT SKYBLUE (-3250 5350);
FORCEPROP 1 LAST WATTAGE 1/16W
J 2
(-2750 5275);
DISPLAY 0.489362 (-2750 5275);
PAINT SKYBLUE (-2750 5275);
DISPLAY INVISIBLE (-2750 5275);
FORCEPROP 1 LAST MATERIAL CHIP
J 0
(-2725 5275);
DISPLAY 0.489362 (-2725 5275);
PAINT SKYBLUE (-2725 5275);
DISPLAY INVISIBLE (-2725 5275);
FORCEPROP 1 LAST TOLERANCE 5%
J 0
(-3175 5275);
DISPLAY 0.489362 (-3175 5275);
PAINT SKYBLUE (-3175 5275);
DISPLAY INVISIBLE (-3175 5275);
FORCEPROP 1 LAST PART_NUMBER CS03302JB29
J 0
(-3125 5400);
DISPLAY 0.489362 (-3125 5400);
PAINT SKYBLUE (-3125 5400);
DISPLAY INVISIBLE (-3125 5400);
FORCEPROP 1 LAST PACK_TYPE 0402LF
J 0
(-3100 5275);
DISPLAY 0.489362 (-3100 5275);
PAINT SKYBLUE (-3100 5275);
DISPLAY INVISIBLE (-3100 5275);
FORCEPROP 1 LAST PATH I2203
J 0
(-3200 5500);
DISPLAY 0.978723 (-3200 5500);
PAINT WHITE (-3200 5500);
DISPLAY INVISIBLE (-3200 5500);
FORCEPROP 2 LAST CDS_LIB pure_quanta
J 0
(-3150 5350);
DISPLAY INVISIBLE (-3150 5350);
FORCEADD OFFPAGE..1
R 2
(-2225 5350);
FORCEPROP 2 LAST $XR2 117 
J 0
(-1859 5350);
DISPLAY 0.638298 (-1859 5350);
PAINT MONO (-1859 5350);
FORCEPROP 2 LAST $XR1 75 
J 0
(-1949 5350);
DISPLAY 0.638298 (-1949 5350);
PAINT MONO (-1949 5350);
FORCEPROP 2 LAST $XR0 29 
J 0
(-2039 5350);
DISPLAY 0.638298 (-2039 5350);
PAINT MONO (-2039 5350);
FORCEPROP 1 LAST OFFPAGE TRUE
J 2
(-2550 5225);
DISPLAY 0.872340 (-2550 5225);
PAINT GREEN (-2550 5225);
DISPLAY INVISIBLE (-2550 5225);
FORCEPROP 1 LAST COMMENT_BODY TRUE
J 2
(-2350 5250);
DISPLAY 0.872340 (-2350 5250);
PAINT GREEN (-2350 5250);
DISPLAY INVISIBLE (-2350 5250);
FORCEPROP 2 LAST PATH I2204
J 0
(-2050 5425);
DISPLAY 0.680851 (-2050 5425);
DISPLAY INVISIBLE (-2050 5425);
FORCEPROP 2 LAST CDS_LIB standard
J 0
(-2225 5350);
DISPLAY INVISIBLE (-2225 5350);
FORCEADD Q_RES..1
(-3150 5250);
FORCEPROP 1 LAST $LOCATION R1557
J 0
(-3025 5250);
DISPLAY 0.510638 (-3025 5250);
PAINT SKYBLUE (-3025 5250);
FORCEPROP 0 LAST CDS_LOCATION R1557
J 0
(-3075 5275);
DISPLAY 0.680851 (-3075 5275);
DISPLAY INVISIBLE (-3075 5275);
FORCEPROP 0 LAST $SEC 1
J 0
(-3075 5275);
DISPLAY 0.680851 (-3075 5275);
PAINT MONO (-3075 5275);
DISPLAY INVISIBLE (-3075 5275);
FORCEPROP 0 LAST CDS_SEC 1
J 0
(-3075 5275);
DISPLAY 0.680851 (-3075 5275);
DISPLAY INVISIBLE (-3075 5275);
FORCEPROP 1 LASTPIN (-3250 5250) $PN 1
J 0
(-3238 5262);
DISPLAY 0.787234 (-3238 5262);
PAINT MONO (-3238 5262);
FORCEPROP 1 LASTPIN (-3050 5250) $PN 2
J 0
(-3088 5262);
DISPLAY 0.787234 (-3088 5262);
PAINT MONO (-3088 5262);
FORCEPROP 1 LAST VALUE 33
J 2
(-3250 5250);
DISPLAY 0.489362 (-3250 5250);
PAINT SKYBLUE (-3250 5250);
FORCEPROP 2 LAST CDS_LIB pure_quanta
J 0
(-3150 5250);
DISPLAY INVISIBLE (-3150 5250);
FORCEPROP 1 LAST PATH I2205
J 0
(-3200 5400);
DISPLAY 0.978723 (-3200 5400);
PAINT WHITE (-3200 5400);
DISPLAY INVISIBLE (-3200 5400);
FORCEPROP 1 LAST PACK_TYPE 0402LF
J 0
(-3100 5175);
DISPLAY 0.489362 (-3100 5175);
PAINT SKYBLUE (-3100 5175);
DISPLAY INVISIBLE (-3100 5175);
FORCEPROP 1 LAST PART_NUMBER CS03302JB29
J 0
(-3125 5300);
DISPLAY 0.489362 (-3125 5300);
PAINT SKYBLUE (-3125 5300);
DISPLAY INVISIBLE (-3125 5300);
FORCEPROP 1 LAST TOLERANCE 5%
J 0
(-3175 5175);
DISPLAY 0.489362 (-3175 5175);
PAINT SKYBLUE (-3175 5175);
DISPLAY INVISIBLE (-3175 5175);
FORCEPROP 1 LAST MATERIAL CHIP
J 0
(-2725 5175);
DISPLAY 0.489362 (-2725 5175);
PAINT SKYBLUE (-2725 5175);
DISPLAY INVISIBLE (-2725 5175);
FORCEPROP 1 LAST WATTAGE 1/16W
J 2
(-2750 5175);
DISPLAY 0.489362 (-2750 5175);
PAINT SKYBLUE (-2750 5175);
DISPLAY INVISIBLE (-2750 5175);
FORCEADD OFFPAGE..1
R 2
(-2225 5250);
FORCEPROP 2 LAST $XR1 117 
J 0
(-1949 5250);
DISPLAY 0.638298 (-1949 5250);
PAINT MONO (-1949 5250);
FORCEPROP 2 LAST $XR0 29 
J 0
(-2039 5250);
DISPLAY 0.638298 (-2039 5250);
PAINT MONO (-2039 5250);
FORCEPROP 2 LAST CDS_LIB standard
J 0
(-2225 5250);
DISPLAY INVISIBLE (-2225 5250);
FORCEPROP 2 LAST PATH I2206
J 0
(-2050 5325);
DISPLAY 0.680851 (-2050 5325);
DISPLAY INVISIBLE (-2050 5325);
FORCEPROP 1 LAST OFFPAGE TRUE
J 2
(-2550 5125);
DISPLAY 0.872340 (-2550 5125);
PAINT GREEN (-2550 5125);
DISPLAY INVISIBLE (-2550 5125);
FORCEPROP 1 LAST COMMENT_BODY TRUE
J 2
(-2350 5150);
DISPLAY 0.872340 (-2350 5150);
PAINT GREEN (-2350 5150);
DISPLAY INVISIBLE (-2350 5150);
FORCEADD Q_RES..1
(-3150 5200);
FORCEPROP 1 LAST $LOCATION R1558
J 0
(-3025 5200);
DISPLAY 0.510638 (-3025 5200);
PAINT SKYBLUE (-3025 5200);
FORCEPROP 0 LAST CDS_LOCATION R1558
J 0
(-3075 5225);
DISPLAY 0.680851 (-3075 5225);
DISPLAY INVISIBLE (-3075 5225);
FORCEPROP 0 LAST $SEC 1
J 0
(-3075 5225);
DISPLAY 0.680851 (-3075 5225);
PAINT MONO (-3075 5225);
DISPLAY INVISIBLE (-3075 5225);
FORCEPROP 0 LAST CDS_SEC 1
J 0
(-3075 5225);
DISPLAY 0.680851 (-3075 5225);
DISPLAY INVISIBLE (-3075 5225);
FORCEPROP 1 LASTPIN (-3250 5200) $PN 1
J 0
(-3238 5212);
DISPLAY 0.787234 (-3238 5212);
PAINT MONO (-3238 5212);
FORCEPROP 1 LASTPIN (-3050 5200) $PN 2
J 0
(-3088 5212);
DISPLAY 0.787234 (-3088 5212);
PAINT MONO (-3088 5212);
FORCEPROP 1 LAST VALUE 33
J 2
(-3250 5200);
DISPLAY 0.489362 (-3250 5200);
PAINT SKYBLUE (-3250 5200);
FORCEPROP 1 LAST WATTAGE 1/16W
J 2
(-2750 5125);
DISPLAY 0.489362 (-2750 5125);
PAINT SKYBLUE (-2750 5125);
DISPLAY INVISIBLE (-2750 5125);
FORCEPROP 1 LAST MATERIAL CHIP
J 0
(-2725 5125);
DISPLAY 0.489362 (-2725 5125);
PAINT SKYBLUE (-2725 5125);
DISPLAY INVISIBLE (-2725 5125);
FORCEPROP 1 LAST TOLERANCE 5%
J 0
(-3175 5125);
DISPLAY 0.489362 (-3175 5125);
PAINT SKYBLUE (-3175 5125);
DISPLAY INVISIBLE (-3175 5125);
FORCEPROP 1 LAST PART_NUMBER CS03302JB29
J 0
(-3125 5250);
DISPLAY 0.489362 (-3125 5250);
PAINT SKYBLUE (-3125 5250);
DISPLAY INVISIBLE (-3125 5250);
FORCEPROP 1 LAST PACK_TYPE 0402LF
J 0
(-3100 5125);
DISPLAY 0.489362 (-3100 5125);
PAINT SKYBLUE (-3100 5125);
DISPLAY INVISIBLE (-3100 5125);
FORCEPROP 1 LAST PATH I2207
J 0
(-3200 5350);
DISPLAY 0.978723 (-3200 5350);
PAINT WHITE (-3200 5350);
DISPLAY INVISIBLE (-3200 5350);
FORCEPROP 2 LAST CDS_LIB pure_quanta
J 0
(-3150 5200);
DISPLAY INVISIBLE (-3150 5200);
FORCEADD OFFPAGE..1
R 2
(-2225 5200);
FORCEPROP 2 LAST $XR1 117 
J 0
(-1949 5200);
DISPLAY 0.638298 (-1949 5200);
PAINT MONO (-1949 5200);
FORCEPROP 2 LAST $XR0 29 
J 0
(-2039 5200);
DISPLAY 0.638298 (-2039 5200);
PAINT MONO (-2039 5200);
FORCEPROP 1 LAST COMMENT_BODY TRUE
J 2
(-2350 5100);
DISPLAY 0.872340 (-2350 5100);
PAINT GREEN (-2350 5100);
DISPLAY INVISIBLE (-2350 5100);
FORCEPROP 1 LAST OFFPAGE TRUE
J 2
(-2550 5075);
DISPLAY 0.872340 (-2550 5075);
PAINT GREEN (-2550 5075);
DISPLAY INVISIBLE (-2550 5075);
FORCEPROP 2 LAST PATH I2208
J 0
(-2050 5275);
DISPLAY 0.680851 (-2050 5275);
DISPLAY INVISIBLE (-2050 5275);
FORCEPROP 2 LAST CDS_LIB standard
J 0
(-2225 5200);
DISPLAY INVISIBLE (-2225 5200);
FORCEADD Q_RES..1
(-6500 2500);
FORCEPROP 1 LAST $LOCATION R1563
J 0
(-6375 2500);
DISPLAY 0.489362 (-6375 2500);
PAINT SKYBLUE (-6375 2500);
FORCEPROP 0 LAST CDS_LOCATION R1563
J 0
(-6375 2525);
DISPLAY 0.680851 (-6375 2525);
DISPLAY INVISIBLE (-6375 2525);
FORCEPROP 0 LAST $SEC 1
J 0
(-6375 2525);
DISPLAY 0.680851 (-6375 2525);
PAINT MONO (-6375 2525);
DISPLAY INVISIBLE (-6375 2525);
FORCEPROP 0 LAST CDS_SEC 1
J 0
(-6375 2525);
DISPLAY 0.680851 (-6375 2525);
DISPLAY INVISIBLE (-6375 2525);
FORCEPROP 1 LASTPIN (-6600 2500) $PN 1
J 0
(-6588 2512);
DISPLAY 0.787234 (-6588 2512);
PAINT MONO (-6588 2512);
FORCEPROP 1 LASTPIN (-6400 2500) $PN 2
J 0
(-6438 2512);
DISPLAY 0.787234 (-6438 2512);
PAINT MONO (-6438 2512);
FORCEPROP 1 LAST VALUE 33
J 2
(-6625 2500);
DISPLAY 0.489362 (-6625 2500);
PAINT SKYBLUE (-6625 2500);
FORCEPROP 2 LAST BOM_COST MEM
J 2
(-6475 2650);
DISPLAY 0.744681 (-6475 2650);
PAINT WHITE (-6475 2650);
DISPLAY INVISIBLE (-6475 2650);
FORCEPROP 1 LAST WATTAGE 1/16W
J 2
(-6575 2425);
DISPLAY 0.489362 (-6575 2425);
PAINT SKYBLUE (-6575 2425);
DISPLAY INVISIBLE (-6575 2425);
FORCEPROP 1 LAST MATERIAL CHIP
J 2
(-6325 2475);
DISPLAY 0.489362 (-6325 2475);
PAINT SKYBLUE (-6325 2475);
DISPLAY INVISIBLE (-6325 2475);
FORCEPROP 1 LAST TOLERANCE 5%
J 0
(-6625 2475);
DISPLAY 0.489362 (-6625 2475);
PAINT SKYBLUE (-6625 2475);
DISPLAY INVISIBLE (-6625 2475);
FORCEPROP 1 LAST PART_NUMBER CS03302JB29
J 2
(-6400 2550);
DISPLAY 0.489362 (-6400 2550);
PAINT SKYBLUE (-6400 2550);
DISPLAY INVISIBLE (-6400 2550);
FORCEPROP 1 LAST PACK_TYPE 0402LF
J 2
(-6325 2425);
DISPLAY 0.489362 (-6325 2425);
PAINT SKYBLUE (-6325 2425);
DISPLAY INVISIBLE (-6325 2425);
FORCEPROP 2 LAST ROOM RST_CPU0_PLD_TO_DIMM
J 2
(-6475 2600);
DISPLAY 0.744681 (-6475 2600);
PAINT RED (-6475 2600);
DISPLAY INVISIBLE (-6475 2600);
FORCEPROP 1 LAST PATH I2209
J 0
(-6550 2650);
DISPLAY 0.978723 (-6550 2650);
PAINT WHITE (-6550 2650);
DISPLAY INVISIBLE (-6550 2650);
FORCEPROP 2 LAST CDS_LIB pure_quanta
J 0
(-6500 2500);
DISPLAY INVISIBLE (-6500 2500);
FORCEADD OFFPAGE..5
(-7475 2500);
FORCEPROP 2 LAST $XR0 141 
J 0
(-7730 2500);
DISPLAY 0.638298 (-7730 2500);
PAINT MONO (-7730 2500);
FORCEPROP 1 LAST OFFPAGE TRUE
J 0
(-7150 2375);
DISPLAY 0.872340 (-7150 2375);
PAINT GREEN (-7150 2375);
DISPLAY INVISIBLE (-7150 2375);
FORCEPROP 1 LAST COMMENT_BODY TRUE
J 0
(-7375 2425);
DISPLAY 0.872340 (-7375 2425);
PAINT GREEN (-7375 2425);
DISPLAY INVISIBLE (-7375 2425);
FORCEPROP 2 LAST PATH I2210
J 0
(-7425 2575);
DISPLAY 0.680851 (-7425 2575);
DISPLAY INVISIBLE (-7425 2575);
FORCEPROP 2 LAST CDS_LIB standard
J 0
(-7475 2500);
DISPLAY INVISIBLE (-7475 2500);
FORCEADD Q_RES..1
(-3150 4150);
FORCEPROP 1 LAST LOCATION R1564
J 0
(-3025 4150);
DISPLAY 0.489362 (-3025 4150);
PAINT SKYBLUE (-3025 4150);
FORCEPROP 0 LAST $SEC 1
J 0
(-3025 4175);
DISPLAY 0.680851 (-3025 4175);
PAINT MONO (-3025 4175);
DISPLAY INVISIBLE (-3025 4175);
FORCEPROP 0 LAST CDS_SEC 1
J 0
(-3025 4175);
DISPLAY 0.680851 (-3025 4175);
DISPLAY INVISIBLE (-3025 4175);
FORCEPROP 1 LASTPIN (-3250 4150) $PN 1
J 0
(-3238 4162);
DISPLAY 0.787234 (-3238 4162);
PAINT MONO (-3238 4162);
FORCEPROP 1 LASTPIN (-3050 4150) $PN 2
J 0
(-3088 4162);
DISPLAY 0.787234 (-3088 4162);
PAINT MONO (-3088 4162);
FORCEPROP 1 LAST VALUE 33
J 2
(-3275 4150);
DISPLAY 0.489362 (-3275 4150);
PAINT SKYBLUE (-3275 4150);
FORCEPROP 2 LAST CDS_LIB pure_quanta
J 0
(-3150 4150);
DISPLAY INVISIBLE (-3150 4150);
FORCEPROP 1 LAST PATH I2211
J 0
(-3200 4300);
DISPLAY 0.978723 (-3200 4300);
PAINT WHITE (-3200 4300);
DISPLAY INVISIBLE (-3200 4300);
FORCEPROP 2 LAST BOM_COST MEM
J 2
(-3125 4300);
DISPLAY 0.744681 (-3125 4300);
PAINT WHITE (-3125 4300);
DISPLAY INVISIBLE (-3125 4300);
FORCEPROP 1 LAST WATTAGE 1/16W
J 2
(-3225 4075);
DISPLAY 0.489362 (-3225 4075);
PAINT SKYBLUE (-3225 4075);
DISPLAY INVISIBLE (-3225 4075);
FORCEPROP 1 LAST MATERIAL CHIP
J 2
(-2975 4125);
DISPLAY 0.489362 (-2975 4125);
PAINT SKYBLUE (-2975 4125);
DISPLAY INVISIBLE (-2975 4125);
FORCEPROP 1 LAST TOLERANCE 5%
J 0
(-3275 4125);
DISPLAY 0.489362 (-3275 4125);
PAINT SKYBLUE (-3275 4125);
DISPLAY INVISIBLE (-3275 4125);
FORCEPROP 1 LAST PART_NUMBER CS03302JB29
J 2
(-3050 4200);
DISPLAY 0.489362 (-3050 4200);
PAINT SKYBLUE (-3050 4200);
DISPLAY INVISIBLE (-3050 4200);
FORCEPROP 1 LAST PACK_TYPE 0402LF
J 2
(-2975 4075);
DISPLAY 0.489362 (-2975 4075);
PAINT SKYBLUE (-2975 4075);
DISPLAY INVISIBLE (-2975 4075);
FORCEPROP 2 LAST ROOM RST_CPU0_PLD_TO_DIMM
J 2
(-3125 4250);
DISPLAY 0.744681 (-3125 4250);
PAINT RED (-3125 4250);
DISPLAY INVISIBLE (-3125 4250);
FORCEADD OFFPAGE..2
(-2225 4150);
FORCEPROP 2 LAST $XR0 76 
J 0
(-2036 4150);
DISPLAY 0.638298 (-2036 4150);
PAINT MONO (-2036 4150);
FORCEPROP 2 LAST CDS_LIB standard
J 0
(-2225 4150);
DISPLAY INVISIBLE (-2225 4150);
FORCEPROP 2 LAST PATH I2212
J 0
(-2050 4225);
DISPLAY 0.680851 (-2050 4225);
DISPLAY INVISIBLE (-2050 4225);
FORCEPROP 1 LAST OFFPAGE TRUE
J 0
(-1900 4025);
DISPLAY 0.872340 (-1900 4025);
PAINT GREEN (-1900 4025);
DISPLAY INVISIBLE (-1900 4025);
FORCEPROP 1 LAST COMMENT_BODY TRUE
J 0
(-2270 4055);
DISPLAY 0.872340 (-2270 4055);
PAINT GREEN (-2270 4055);
DISPLAY INVISIBLE (-2270 4055);
FORCEADD Q_RES..1
(-3150 4100);
FORCEPROP 1 LAST $LOCATION R1616
J 0
(-3025 4100);
DISPLAY 0.489362 (-3025 4100);
PAINT SKYBLUE (-3025 4100);
FORCEPROP 0 LAST CDS_LOCATION R1616
J 0
(-3025 4125);
DISPLAY 0.680851 (-3025 4125);
DISPLAY INVISIBLE (-3025 4125);
FORCEPROP 0 LAST $SEC 1
J 0
(-3025 4125);
DISPLAY 0.680851 (-3025 4125);
PAINT MONO (-3025 4125);
DISPLAY INVISIBLE (-3025 4125);
FORCEPROP 0 LAST CDS_SEC 1
J 0
(-3025 4125);
DISPLAY 0.680851 (-3025 4125);
DISPLAY INVISIBLE (-3025 4125);
FORCEPROP 1 LASTPIN (-3250 4100) $PN 1
J 0
(-3238 4112);
DISPLAY 0.787234 (-3238 4112);
PAINT MONO (-3238 4112);
FORCEPROP 1 LASTPIN (-3050 4100) $PN 2
J 0
(-3088 4112);
DISPLAY 0.787234 (-3088 4112);
PAINT MONO (-3088 4112);
FORCEPROP 1 LAST VALUE 33
J 2
(-3275 4100);
DISPLAY 0.489362 (-3275 4100);
PAINT SKYBLUE (-3275 4100);
FORCEPROP 2 LAST ROOM RST_CPU0_PLD_TO_DIMM
J 2
(-3125 4200);
DISPLAY 0.744681 (-3125 4200);
PAINT RED (-3125 4200);
DISPLAY INVISIBLE (-3125 4200);
FORCEPROP 1 LAST PACK_TYPE 0402LF
J 2
(-2975 4025);
DISPLAY 0.489362 (-2975 4025);
PAINT SKYBLUE (-2975 4025);
DISPLAY INVISIBLE (-2975 4025);
FORCEPROP 1 LAST PART_NUMBER CS03302JB29
J 2
(-3050 4150);
DISPLAY 0.489362 (-3050 4150);
PAINT SKYBLUE (-3050 4150);
DISPLAY INVISIBLE (-3050 4150);
FORCEPROP 1 LAST TOLERANCE 5%
J 0
(-3275 4075);
DISPLAY 0.489362 (-3275 4075);
PAINT SKYBLUE (-3275 4075);
DISPLAY INVISIBLE (-3275 4075);
FORCEPROP 1 LAST MATERIAL CHIP
J 2
(-2975 4075);
DISPLAY 0.489362 (-2975 4075);
PAINT SKYBLUE (-2975 4075);
DISPLAY INVISIBLE (-2975 4075);
FORCEPROP 1 LAST WATTAGE 1/16W
J 2
(-3225 4025);
DISPLAY 0.489362 (-3225 4025);
PAINT SKYBLUE (-3225 4025);
DISPLAY INVISIBLE (-3225 4025);
FORCEPROP 2 LAST BOM_COST MEM
J 2
(-3125 4250);
DISPLAY 0.744681 (-3125 4250);
PAINT WHITE (-3125 4250);
DISPLAY INVISIBLE (-3125 4250);
FORCEPROP 1 LAST PATH I2213
J 0
(-3200 4250);
DISPLAY 0.978723 (-3200 4250);
PAINT WHITE (-3200 4250);
DISPLAY INVISIBLE (-3200 4250);
FORCEPROP 2 LAST CDS_LIB pure_quanta
J 0
(-3150 4100);
DISPLAY INVISIBLE (-3150 4100);
FORCEADD OFFPAGE..2
(-2225 4100);
FORCEPROP 2 LAST $XR0 76 
J 0
(-2036 4100);
DISPLAY 0.638298 (-2036 4100);
PAINT MONO (-2036 4100);
FORCEPROP 1 LAST COMMENT_BODY TRUE
J 0
(-2270 4005);
DISPLAY 0.872340 (-2270 4005);
PAINT GREEN (-2270 4005);
DISPLAY INVISIBLE (-2270 4005);
FORCEPROP 1 LAST OFFPAGE TRUE
J 0
(-1900 3975);
DISPLAY 0.872340 (-1900 3975);
PAINT GREEN (-1900 3975);
DISPLAY INVISIBLE (-1900 3975);
FORCEPROP 2 LAST PATH I2214
J 0
(-2050 4175);
DISPLAY 0.680851 (-2050 4175);
DISPLAY INVISIBLE (-2050 4175);
FORCEPROP 2 LAST CDS_LIB standard
J 0
(-2225 4100);
DISPLAY INVISIBLE (-2225 4100);
FORCEADD Q_RES..1
(-3150 3950);
FORCEPROP 1 LAST LOCATION R195
J 0
(-3025 3950);
DISPLAY 0.489362 (-3025 3950);
PAINT SKYBLUE (-3025 3950);
FORCEPROP 0 LAST $SEC 1
J 0
(-3025 3975);
DISPLAY 0.680851 (-3025 3975);
PAINT MONO (-3025 3975);
DISPLAY INVISIBLE (-3025 3975);
FORCEPROP 0 LAST CDS_SEC 1
J 0
(-3025 3975);
DISPLAY 0.680851 (-3025 3975);
DISPLAY INVISIBLE (-3025 3975);
FORCEPROP 1 LASTPIN (-3250 3950) $PN 1
J 0
(-3238 3962);
DISPLAY 0.787234 (-3238 3962);
PAINT MONO (-3238 3962);
FORCEPROP 1 LASTPIN (-3050 3950) $PN 2
J 0
(-3088 3962);
DISPLAY 0.787234 (-3088 3962);
PAINT MONO (-3088 3962);
FORCEPROP 1 LAST VALUE 0
J 2
(-3275 3950);
DISPLAY 0.489362 (-3275 3950);
PAINT SKYBLUE (-3275 3950);
FORCEPROP 2 LAST CDS_LIB pure_quanta
J 0
(-3150 3950);
DISPLAY INVISIBLE (-3150 3950);
FORCEPROP 1 LAST PATH I2215
J 0
(-3200 4100);
DISPLAY 0.978723 (-3200 4100);
PAINT WHITE (-3200 4100);
DISPLAY INVISIBLE (-3200 4100);
FORCEPROP 2 LAST BOM_COST MEM
J 2
(-3125 4100);
DISPLAY 0.744681 (-3125 4100);
PAINT WHITE (-3125 4100);
DISPLAY INVISIBLE (-3125 4100);
FORCEPROP 1 LAST WATTAGE 1/16W
J 2
(-3225 3875);
DISPLAY 0.489362 (-3225 3875);
PAINT SKYBLUE (-3225 3875);
DISPLAY INVISIBLE (-3225 3875);
FORCEPROP 1 LAST MATERIAL CHIP
J 2
(-2975 3925);
DISPLAY 0.489362 (-2975 3925);
PAINT SKYBLUE (-2975 3925);
DISPLAY INVISIBLE (-2975 3925);
FORCEPROP 1 LAST TOLERANCE 5%
J 0
(-3275 3925);
DISPLAY 0.489362 (-3275 3925);
PAINT SKYBLUE (-3275 3925);
DISPLAY INVISIBLE (-3275 3925);
FORCEPROP 1 LAST PART_NUMBER CS00002JB38
J 2
(-3050 4000);
DISPLAY 0.489362 (-3050 4000);
PAINT SKYBLUE (-3050 4000);
DISPLAY INVISIBLE (-3050 4000);
FORCEPROP 1 LAST PACK_TYPE 0402LF
J 2
(-2975 3875);
DISPLAY 0.489362 (-2975 3875);
PAINT SKYBLUE (-2975 3875);
DISPLAY INVISIBLE (-2975 3875);
FORCEPROP 2 LAST ROOM RST_CPU0_PLD_TO_DIMM
J 2
(-3125 4050);
DISPLAY 0.744681 (-3125 4050);
PAINT RED (-3125 4050);
DISPLAY INVISIBLE (-3125 4050);
FORCEADD OFFPAGE..1
R 2
(-2225 3950);
FORCEPROP 2 LAST $XR0 55 
J 0
(-2039 3950);
DISPLAY 0.638298 (-2039 3950);
PAINT MONO (-2039 3950);
FORCEPROP 2 LAST CDS_LIB standard
J 0
(-2225 3950);
DISPLAY INVISIBLE (-2225 3950);
FORCEPROP 2 LAST PATH I2216
J 0
(-2050 4025);
DISPLAY 0.680851 (-2050 4025);
DISPLAY INVISIBLE (-2050 4025);
FORCEPROP 1 LAST OFFPAGE TRUE
J 2
(-2550 3825);
DISPLAY 0.872340 (-2550 3825);
PAINT GREEN (-2550 3825);
DISPLAY INVISIBLE (-2550 3825);
FORCEPROP 1 LAST COMMENT_BODY TRUE
J 2
(-2350 3850);
DISPLAY 0.872340 (-2350 3850);
PAINT GREEN (-2350 3850);
DISPLAY INVISIBLE (-2350 3850);
FORCEADD Q_RES..1
(-3150 3900);
FORCEPROP 1 LAST LOCATION R252
J 0
(-3025 3900);
DISPLAY 0.489362 (-3025 3900);
PAINT SKYBLUE (-3025 3900);
FORCEPROP 0 LAST $SEC 1
J 0
(-3025 3925);
DISPLAY 0.680851 (-3025 3925);
PAINT MONO (-3025 3925);
DISPLAY INVISIBLE (-3025 3925);
FORCEPROP 0 LAST CDS_SEC 1
J 0
(-3025 3925);
DISPLAY 0.680851 (-3025 3925);
DISPLAY INVISIBLE (-3025 3925);
FORCEPROP 1 LASTPIN (-3250 3900) $PN 1
J 0
(-3238 3912);
DISPLAY 0.787234 (-3238 3912);
PAINT MONO (-3238 3912);
FORCEPROP 1 LASTPIN (-3050 3900) $PN 2
J 0
(-3088 3912);
DISPLAY 0.787234 (-3088 3912);
PAINT MONO (-3088 3912);
FORCEPROP 1 LAST VALUE 0
J 2
(-3275 3900);
DISPLAY 0.489362 (-3275 3900);
PAINT SKYBLUE (-3275 3900);
FORCEPROP 2 LAST ROOM RST_CPU0_PLD_TO_DIMM
J 2
(-3125 4000);
DISPLAY 0.744681 (-3125 4000);
PAINT RED (-3125 4000);
DISPLAY INVISIBLE (-3125 4000);
FORCEPROP 1 LAST PACK_TYPE 0402LF
J 2
(-2975 3825);
DISPLAY 0.489362 (-2975 3825);
PAINT SKYBLUE (-2975 3825);
DISPLAY INVISIBLE (-2975 3825);
FORCEPROP 1 LAST PART_NUMBER CS00002JB38
J 2
(-3050 3950);
DISPLAY 0.489362 (-3050 3950);
PAINT SKYBLUE (-3050 3950);
DISPLAY INVISIBLE (-3050 3950);
FORCEPROP 1 LAST TOLERANCE 5%
J 0
(-3275 3875);
DISPLAY 0.489362 (-3275 3875);
PAINT SKYBLUE (-3275 3875);
DISPLAY INVISIBLE (-3275 3875);
FORCEPROP 1 LAST MATERIAL CHIP
J 2
(-2975 3875);
DISPLAY 0.489362 (-2975 3875);
PAINT SKYBLUE (-2975 3875);
DISPLAY INVISIBLE (-2975 3875);
FORCEPROP 1 LAST WATTAGE 1/16W
J 2
(-3225 3825);
DISPLAY 0.489362 (-3225 3825);
PAINT SKYBLUE (-3225 3825);
DISPLAY INVISIBLE (-3225 3825);
FORCEPROP 2 LAST BOM_COST MEM
J 2
(-3125 4050);
DISPLAY 0.744681 (-3125 4050);
PAINT WHITE (-3125 4050);
DISPLAY INVISIBLE (-3125 4050);
FORCEPROP 1 LAST PATH I2217
J 0
(-3200 4050);
DISPLAY 0.978723 (-3200 4050);
PAINT WHITE (-3200 4050);
DISPLAY INVISIBLE (-3200 4050);
FORCEPROP 2 LAST CDS_LIB pure_quanta
J 0
(-3150 3900);
DISPLAY INVISIBLE (-3150 3900);
FORCEADD OFFPAGE..1
R 2
(-2225 3900);
FORCEPROP 2 LAST $XR1 55 
J 0
(-1949 3900);
DISPLAY 0.638298 (-1949 3900);
PAINT MONO (-1949 3900);
FORCEPROP 2 LAST $XR0 28 
J 0
(-2039 3900);
DISPLAY 0.638298 (-2039 3900);
PAINT MONO (-2039 3900);
FORCEPROP 1 LAST COMMENT_BODY TRUE
J 2
(-2350 3800);
DISPLAY 0.872340 (-2350 3800);
PAINT GREEN (-2350 3800);
DISPLAY INVISIBLE (-2350 3800);
FORCEPROP 1 LAST OFFPAGE TRUE
J 2
(-2550 3775);
DISPLAY 0.872340 (-2550 3775);
PAINT GREEN (-2550 3775);
DISPLAY INVISIBLE (-2550 3775);
FORCEPROP 2 LAST PATH I2218
J 0
(-2050 3975);
DISPLAY 0.680851 (-2050 3975);
DISPLAY INVISIBLE (-2050 3975);
FORCEPROP 2 LAST CDS_LIB standard
J 0
(-2225 3900);
DISPLAY INVISIBLE (-2225 3900);
FORCEADD DNS..2
(-6375 5225);
PAINT RED (-6375 5225);
FORCEPROP 2 LAST CDS_LIB mstr_misc
J 0
(-6375 5225);
DISPLAY INVISIBLE (-6375 5225);
FORCEPROP 1 LAST COMMENT_BODY TRUE
R 1
J 0
(-6300 5000);
DISPLAY 0.872340 (-6300 5000);
PAINT PEACH (-6300 5000);
DISPLAY INVISIBLE (-6300 5000);
FORCEADD QUANTA_TITLE_BLOCK_C..1
(0 0);
FORCEPROP 0 LAST CDS_CON_LAST_MODIFIED Fri Mar 11 14:53:20 2022
J 0
(-1885 15);
DISPLAY INVISIBLE (-1885 15);
FORCEPROP 1 LAST CUSTOM_TXT_CDS <CON_LAST_MODIFIED>
J 0
(-1885 15);
DISPLAY 0.978723 (-1885 15);
FORCEPROP 2 LAST CUSTOM_TXT_CDS <XR_PAGE_TITLE>
J 0
(-7890 5250);
DISPLAY 0.638298 (-7890 5250);
PAINT PINK (-7890 5250);
DISPLAY INVISIBLE (-7890 5250);
FORCEPROP 1 LAST CUSTOM_TXT_CDS <NAME_2>
J 0
(-3175 50);
FORCEPROP 1 LAST CUSTOM_TXT_CDS <NAME_1>
J 0
(-3175 175);
FORCEPROP 1 LAST CUSTOM_TXT_CDS <Q_NUMBER>
J 0
(-1403 103);
DISPLAY 1.212766 (-1403 103);
FORCEPROP 1 LAST CUSTOM_TXT_CDS <Q_PROJ>
J 0
(-2382 102);
DISPLAY 1.212766 (-2382 102);
FORCEPROP 1 LAST CUSTOM_TXT_CDS <Q_REV>
J 0
(-184 103);
DISPLAY 1.212766 (-184 103);
FORCEPROP 1 LAST CUSTOM_TXT_CDS <CON_PAGE_NUM> OF <CON_TOTAL_PAGES>
J 0
(-446 18);
DISPLAY 0.978723 (-446 18);
FORCEPROP 1 LAST Q_DEPT BU9
J 1
(-3763 49);
DISPLAY 1.957447 (-3763 49);
PAINT GREEN (-3763 49);
FORCEPROP 1 LAST Q_TITLE FPGA 2/6
J 0
(-9275 75);
DISPLAY 2.446809 (-9275 75);
PAINT GREEN (-9275 75);
FORCEPROP 1 LAST COMMENT_BODY TRUE
J 0
(12 -13);
DISPLAY 0.978723 (12 -13);
PAINT GREEN (12 -13);
DISPLAY INVISIBLE (12 -13);
FORCEPROP 2 LAST CDS_LIB pure_quanta
J 0
(0 0);
DISPLAY INVISIBLE (0 0);
FORCEPROP 1 LAST CDS_LMAN_SYM_OUTLINE -9475,6775,100,-125
J 0
(0 0);
DISPLAY 0.468085 (0 0);
PAINT GREEN (0 0);
DISPLAY INVISIBLE (0 0);
FORCEPROP 2 LAST PAGE_BORDER TRUE
J 0
(-7890 5250);
DISPLAY 0.638298 (-7890 5250);
PAINT PINK (-7890 5250);
DISPLAY INVISIBLE (-7890 5250);
FORCEPROP 2 LAST CDS_XR_PAGE_TITLE CR-80 : @T6G_MB_LIB.T6G(SCH_1):PAGE80
J 0
(-7890 5250);
DISPLAY 0.638298 (-7890 5250);
PAINT PINK (-7890 5250);
DISPLAY INVISIBLE (-7890 5250);
WIRE 16 -1 (-7425 2150)(-5300 2150);
FORCEPROP 2 LAST SIG_NAME FM_PWRGD_PVDD33_S5
J 0
(-7300 2155);
DISPLAY 0.489362 (-7300 2155);
WIRE 16 -1 (-7450 2100)(-5300 2100);
FORCEPROP 2 LAST SIG_NAME FM_LED_D2
J 0
(-7310 2110);
DISPLAY 0.446809 (-7310 2110);
WIRE 16 -1 (-7450 2050)(-5300 2050);
FORCEPROP 2 LAST SIG_NAME FM_LED_D3
J 0
(-7310 2060);
DISPLAY 0.446809 (-7310 2060);
WIRE 16 -1 (-6600 2000)(-7425 2000);
FORCEPROP 2 LAST SIG_NAME PVDD11_S3_P1_EN
J 0
(-7300 2010);
DISPLAY 0.489362 (-7300 2010);
WIRE 16 -1 (-6600 1950)(-7425 1950);
FORCEPROP 2 LAST SIG_NAME PWRGD_PVDD11_S3_P1
J 0
(-7300 1960);
DISPLAY 0.489362 (-7300 1960);
WIRE 16 -1 (-7425 1900)(-6600 1900);
FORCEPROP 2 LAST SIG_NAME PVDD18_S5_P1_EN
J 0
(-7300 1910);
DISPLAY 0.489362 (-7300 1910);
WIRE 16 -1 (-5300 1800)(-7425 1800);
FORCEPROP 0 LAST CDS_PHYS_NET_NAME SPI_PLD_CLK
J 2
(-5575 1850);
PAINT MONO (-5575 1850);
DISPLAY INVISIBLE (-5575 1850);
FORCEPROP 2 LAST SIG_NAME SPI_PLD_CLK
J 0
(-6125 1810);
DISPLAY 0.489362 (-6125 1810);
WIRE 16 -1 (-5300 1750)(-7425 1750);
FORCEPROP 0 LAST CDS_PHYS_NET_NAME SPI_PLD_D1
J 2
(-5575 1800);
PAINT MONO (-5575 1800);
DISPLAY INVISIBLE (-5575 1800);
FORCEPROP 2 LAST SIG_NAME SPI_PLD_D1
J 0
(-6125 1760);
DISPLAY 0.489362 (-6125 1760);
WIRE 16 -1 (-5300 1600)(-6400 1600);
FORCEPROP 2 LAST SIG_NAME FM_PVDD18_S5_P0_EN
J 0
(-6125 1605);
DISPLAY 0.489362 (-6125 1605);
FORCEPROP 2 LASTPROP $XRERR UNIQUE?
J 0
(-6365 1605);
DISPLAY 0.638298 (-6365 1605);
PAINT MONO (-6365 1605);
DISPLAY INVISIBLE (-6365 1605);
WIRE 16 -1 (-7425 1550)(-5300 1550);
FORCEPROP 2 LAST SIG_NAME FM_PWRGD_PVDD18_S5_P0
J 0
(-7300 1555);
DISPLAY 0.489362 (-7300 1555);
WIRE 16 -1 (-5300 1450)(-6400 1450);
FORCEPROP 2 LAST SIG_NAME FM_CPU0_PWR_GOOD
J 0
(-6125 1455);
DISPLAY 0.489362 (-6125 1455);
FORCEPROP 2 LASTPROP $XRERR UNIQUE?
J 0
(-6365 1455);
DISPLAY 0.638298 (-6365 1455);
PAINT MONO (-6365 1455);
DISPLAY INVISIBLE (-6365 1455);
WIRE 16 -1 (-5300 1400)(-6400 1400);
FORCEPROP 2 LAST SIG_NAME FM_PVDDIO_P1_EN
J 0
(-6125 1405);
DISPLAY 0.489362 (-6125 1405);
FORCEPROP 2 LASTPROP $XRERR UNIQUE?
J 0
(-6365 1405);
DISPLAY 0.638298 (-6365 1405);
PAINT MONO (-6365 1405);
DISPLAY INVISIBLE (-6365 1405);
WIRE 16 -1 (-7425 1500)(-5300 1500);
FORCEPROP 2 LAST SIG_NAME PWRGD_P1V8_STBY_R
J 0
(-7300 1505);
DISPLAY 0.489362 (-7300 1505);
WIRE 16 -1 (-6400 1150)(-5300 1150);
FORCEPROP 2 LAST SIG_NAME FM_PLD_OCP_SFF_PWR_GOOD_R
J 0
(-6125 1165);
DISPLAY 0.489362 (-6125 1165);
FORCEPROP 2 LASTPROP $XRERR UNIQUE?
J 0
(-6365 1165);
DISPLAY 0.638298 (-6365 1165);
PAINT MONO (-6365 1165);
DISPLAY INVISIBLE (-6365 1165);
WIRE 16 -1 (-7425 1200)(-5300 1200);
FORCEPROP 2 LAST SIG_NAME P12V_E1S_2_PWRGD
J 0
(-7300 1210);
DISPLAY 0.489362 (-7300 1210);
WIRE 16 -1 (-7425 1250)(-5300 1250);
FORCEPROP 2 LAST SIG_NAME P12V_E1S_1_PWRGD
J 0
(-7300 1260);
DISPLAY 0.489362 (-7300 1260);
WIRE 16 -1 (-7425 1300)(-5300 1300);
FORCEPROP 2 LAST SIG_NAME PWGD_P3V3_E1S_2
J 0
(-7300 1310);
DISPLAY 0.489362 (-7300 1310);
WIRE 16 -1 (-5300 1350)(-6400 1350);
FORCEPROP 2 LAST SIG_NAME FM_PWRGD_PVDDIO_P1
J 0
(-6125 1355);
DISPLAY 0.489362 (-6125 1355);
FORCEPROP 2 LASTPROP $XRERR UNIQUE?
J 0
(-6365 1355);
DISPLAY 0.638298 (-6365 1355);
PAINT MONO (-6365 1355);
DISPLAY INVISIBLE (-6365 1355);
WIRE 16 -1 (-7425 1650)(-5300 1650);
FORCEPROP 2 LAST SIG_NAME PWRGD_P3V3_STBY_R
J 0
(-7300 1655);
DISPLAY 0.489362 (-7300 1655);
WIRE 16 -1 (-6400 1900)(-5300 1900);
FORCEPROP 2 LAST SIG_NAME PVDD18_S5_P1_R_EN
J 0
(-6125 1905);
DISPLAY 0.489362 (-6125 1905);
FORCEPROP 2 LASTPROP $XRERR UNIQUE?
J 0
(-6365 1905);
DISPLAY 0.638298 (-6365 1905);
PAINT MONO (-6365 1905);
DISPLAY INVISIBLE (-6365 1905);
WIRE 16 -1 (-5300 1050)(-7425 1050);
FORCEPROP 2 LAST SIG_NAME BMC_HPM_FPGA_LED2
J 0
(-6125 1060);
DISPLAY 0.489362 (-6125 1060);
WIRE 16 -1 (-6600 1350)(-7425 1350);
FORCEPROP 2 LAST SIG_NAME PWRGD_PVDDIO_P1
J 0
(-7300 1360);
DISPLAY 0.489362 (-7300 1360);
WIRE 16 -1 (-6600 1400)(-7425 1400);
FORCEPROP 2 LAST SIG_NAME PVDDIO_P1_EN
J 0
(-7300 1410);
DISPLAY 0.489362 (-7300 1410);
WIRE 16 -1 (-6600 1450)(-7425 1450);
FORCEPROP 2 LAST SIG_NAME CPU0_PWR_GOOD
J 0
(-7300 1460);
DISPLAY 0.489362 (-7300 1460);
WIRE 16 -1 (-7425 1150)(-6600 1150);
FORCEPROP 2 LAST SIG_NAME FM_PLD_OCP_SFF_PWR_GOOD
J 0
(-7300 1160);
DISPLAY 0.489362 (-7300 1160);
WIRE 16 -1 (-6600 1600)(-7425 1600);
FORCEPROP 2 LAST SIG_NAME PVDD18_S5_P0_EN
J 0
(-7300 1610);
DISPLAY 0.489362 (-7300 1610);
WIRE 16 -1 (-5300 2000)(-6400 2000);
FORCEPROP 2 LAST SIG_NAME FM_PVDD11_S3_P1_EN
J 0
(-6125 2005);
DISPLAY 0.489362 (-6125 2005);
FORCEPROP 2 LASTPROP $XRERR UNIQUE?
J 0
(-6365 2005);
DISPLAY 0.638298 (-6365 2005);
PAINT MONO (-6365 2005);
DISPLAY INVISIBLE (-6365 2005);
WIRE 16 -1 (-7425 2200)(-5300 2200);
FORCEPROP 2 LAST SIG_NAME PWRGD_PVDD18_S5_R_P1
J 0
(-7300 2205);
DISPLAY 0.489362 (-7300 2205);
WIRE 16 -1 (-2275 3650)(-3050 3650);
FORCEPROP 2 LAST SIG_NAME CPU1_FORCE_SELFREFRESH
J 0
(-2875 3660);
DISPLAY 0.489362 (-2875 3660);
WIRE 16 -1 (-2275 3700)(-3050 3700);
FORCEPROP 2 LAST SIG_NAME FM_FORCE_ALL_PWRON
J 0
(-2875 3710);
DISPLAY 0.489362 (-2875 3710);
WIRE 16 -1 (-2275 3800)(-3050 3800);
FORCEPROP 2 LAST SIG_NAME FM_CLK_BUFFER_EN
J 0
(-2875 3810);
DISPLAY 0.489362 (-2875 3810);
WIRE 16 -1 (-2275 3850)(-3050 3850);
FORCEPROP 2 LAST SIG_NAME CPU0_FORCE_SELFREFRESH
J 0
(-2875 3860);
DISPLAY 0.489362 (-2875 3860);
WIRE 16 -1 (-3050 3900)(-2275 3900);
FORCEPROP 2 LAST SIG_NAME CPU1_PWR_GD_IN
J 0
(-2885 3910);
DISPLAY 0.446809 (-2885 3910);
WIRE 16 -1 (-4100 3900)(-3250 3900);
FORCEPROP 2 LAST SIG_NAME FM_CPU1_PWR_GD_IN
J 0
(-3985 3910);
DISPLAY 0.446809 (-3985 3910);
FORCEPROP 2 LASTPROP $XRERR UNIQUE?
J 0
(-4225 3910);
DISPLAY 0.638298 (-4225 3910);
PAINT MONO (-4225 3910);
DISPLAY INVISIBLE (-4225 3910);
WIRE 16 -1 (-3250 3850)(-4100 3850);
FORCEPROP 2 LAST SIG_NAME FM_CPU0_FORCE_SELFREFRESH
J 0
(-3985 3860);
DISPLAY 0.489362 (-3985 3860);
FORCEPROP 2 LASTPROP $XRERR UNIQUE?
J 0
(-4225 3860);
DISPLAY 0.638298 (-4225 3860);
PAINT MONO (-4225 3860);
DISPLAY INVISIBLE (-4225 3860);
WIRE 16 -1 (-4100 3800)(-3250 3800);
FORCEPROP 2 LAST SIG_NAME FM_CLK_BUFFER_EN_R
J 0
(-3985 3810);
DISPLAY 0.489362 (-3985 3810);
FORCEPROP 2 LASTPROP $XRERR UNIQUE?
J 0
(-4225 3810);
DISPLAY 0.638298 (-4225 3810);
PAINT MONO (-4225 3810);
DISPLAY INVISIBLE (-4225 3810);
WIRE 16 -1 (-4100 3700)(-3250 3700);
FORCEPROP 2 LAST SIG_NAME FM_FORCE_ALL_PWRON_R
J 0
(-3985 3710);
DISPLAY 0.489362 (-3985 3710);
FORCEPROP 2 LASTPROP $XRERR UNIQUE?
J 0
(-4225 3710);
DISPLAY 0.638298 (-4225 3710);
PAINT MONO (-4225 3710);
DISPLAY INVISIBLE (-4225 3710);
WIRE 16 -1 (-3250 3650)(-4100 3650);
FORCEPROP 2 LAST SIG_NAME FM_CPU1_FORCE_SELFREFRESH
J 0
(-3985 3660);
DISPLAY 0.489362 (-3985 3660);
FORCEPROP 2 LASTPROP $XRERR UNIQUE?
J 0
(-4225 3660);
DISPLAY 0.638298 (-4225 3660);
PAINT MONO (-4225 3660);
DISPLAY INVISIBLE (-4225 3660);
WIRE 16 -1 (-3250 4400)(-4100 4400);
FORCEPROP 2 LAST SIG_NAME SCM_IRQ_1V8_R_N
J 0
(-3985 4410);
DISPLAY 0.489362 (-3985 4410);
FORCEPROP 2 LASTPROP $XRERR UNIQUE?
J 0
(-4225 4410);
DISPLAY 0.638298 (-4225 4410);
PAINT MONO (-4225 4410);
DISPLAY INVISIBLE (-4225 4410);
WIRE 16 -1 (-4100 4350)(-2275 4350);
FORCEPROP 2 LAST SIG_NAME WC_PRSNT_0_N
J 0
(-2875 4360);
DISPLAY 0.489362 (-2875 4360);
WIRE 16 -1 (-4100 4300)(-3250 4300);
FORCEPROP 2 LAST SIG_NAME P12V_ALL_PWROK_R
J 0
(-3985 4310);
DISPLAY 0.489362 (-3985 4310);
FORCEPROP 2 LASTPROP $XRERR UNIQUE?
J 0
(-4225 4310);
DISPLAY 0.638298 (-4225 4310);
PAINT MONO (-4225 4310);
DISPLAY INVISIBLE (-4225 4310);
WIRE 16 -1 (-4100 4250)(-2275 4250);
FORCEPROP 2 LAST SIG_NAME WC_PRSNT_2_N
J 0
(-2875 4260);
DISPLAY 0.489362 (-2875 4260);
WIRE 16 -1 (-4100 4150)(-3250 4150);
FORCEPROP 2 LAST SIG_NAME FM_ROM_LS_EN
J 0
(-3985 4160);
DISPLAY 0.446809 (-3985 4160);
FORCEPROP 2 LASTPROP $XRERR UNIQUE?
J 0
(-4225 4160);
DISPLAY 0.638298 (-4225 4160);
PAINT MONO (-4225 4160);
DISPLAY INVISIBLE (-4225 4160);
WIRE 16 -1 (-3050 3950)(-2275 3950);
FORCEPROP 2 LAST SIG_NAME CPU1_PWRGD_OUT
J 0
(-2885 3960);
DISPLAY 0.446809 (-2885 3960);
WIRE 16 -1 (-4100 4100)(-3250 4100);
FORCEPROP 2 LAST SIG_NAME FM_ROM_SD_LS_OE
J 0
(-3985 4110);
DISPLAY 0.446809 (-3985 4110);
FORCEPROP 2 LASTPROP $XRERR UNIQUE?
J 0
(-4225 4110);
DISPLAY 0.638298 (-4225 4110);
PAINT MONO (-4225 4110);
DISPLAY INVISIBLE (-4225 4110);
WIRE 16 -1 (-3250 4200)(-4100 4200);
FORCEPROP 2 LAST SIG_NAME BMC_JTAG_SEL_R
J 0
(-3985 4210);
DISPLAY 0.489362 (-3985 4210);
FORCEPROP 2 LASTPROP $XRERR UNIQUE?
J 0
(-4225 4210);
DISPLAY 0.638298 (-4225 4210);
PAINT MONO (-4225 4210);
DISPLAY INVISIBLE (-4225 4210);
WIRE 16 -1 (-4100 4000)(-3250 4000);
FORCEPROP 0 LAST CDS_PHYS_NET_NAME FM_PLD_CPU0_PRSNT_HDT
J 0
(-3825 4050);
PAINT MONO (-3825 4050);
DISPLAY INVISIBLE (-3825 4050);
FORCEPROP 2 LAST SIG_NAME FM_PLD_CPU0_PRSNT_HDT
J 0
(-3985 4010);
DISPLAY 0.489362 (-3985 4010);
FORCEPROP 2 LASTPROP $XRERR UNIQUE?
J 0
(-4225 4010);
DISPLAY 0.638298 (-4225 4010);
PAINT MONO (-4225 4010);
DISPLAY INVISIBLE (-4225 4010);
WIRE 16 -1 (-4100 3950)(-3250 3950);
FORCEPROP 2 LAST SIG_NAME FM_CPU1_PWRGD_OUT
J 0
(-3985 3960);
DISPLAY 0.446809 (-3985 3960);
FORCEPROP 2 LASTPROP $XRERR UNIQUE?
J 0
(-4225 3960);
DISPLAY 0.638298 (-4225 3960);
PAINT MONO (-4225 3960);
DISPLAY INVISIBLE (-4225 3960);
WIRE 16 -1 (-7225 3650)(-5400 3650);
FORCEPROP 2 LAST SIG_NAME PWRGD_P12V_FAN_SR_R
J 0
(-7050 3660);
DISPLAY 0.489362 (-7050 3660);
WIRE 16 -1 (-5300 1700)(-6400 1700);
FORCEPROP 2 LAST SIG_NAME FM_PVDD33_S5_EN
J 0
(-6125 1705);
DISPLAY 0.489362 (-6125 1705);
FORCEPROP 2 LASTPROP $XRERR UNIQUE?
J 0
(-6365 1705);
DISPLAY 0.638298 (-6365 1705);
PAINT MONO (-6365 1705);
DISPLAY INVISIBLE (-6365 1705);
WIRE 16 -1 (-7450 2400)(-5300 2400);
FORCEPROP 2 LAST SIG_NAME FM_LED_D0
J 0
(-7310 2410);
DISPLAY 0.446809 (-7310 2410);
WIRE 16 -1 (-6400 2950)(-5300 2950);
FORCEPROP 2 LAST SIG_NAME PRSNT1_SLOT2_R_N
J 0
(-6125 2960);
DISPLAY 0.489362 (-6125 2960);
FORCEPROP 2 LASTPROP $XRERR UNIQUE?
J 0
(-6365 2960);
DISPLAY 0.638298 (-6365 2960);
PAINT MONO (-6365 2960);
DISPLAY INVISIBLE (-6365 2960);
WIRE 16 -1 (-6400 3000)(-5300 3000);
FORCEPROP 2 LAST SIG_NAME PRSNT1_SLOT1_R_N
J 0
(-6125 3010);
DISPLAY 0.489362 (-6125 3010);
FORCEPROP 2 LASTPROP $XRERR UNIQUE?
J 0
(-6365 3010);
DISPLAY 0.638298 (-6365 3010);
PAINT MONO (-6365 3010);
DISPLAY INVISIBLE (-6365 3010);
WIRE 16 -1 (-5300 1950)(-6400 1950);
FORCEPROP 2 LAST SIG_NAME FM_PWRGD_PVDD11_S3_P1
J 0
(-6125 1955);
DISPLAY 0.489362 (-6125 1955);
FORCEPROP 2 LASTPROP $XRERR UNIQUE?
J 0
(-6365 1955);
DISPLAY 0.638298 (-6365 1955);
PAINT MONO (-6365 1955);
DISPLAY INVISIBLE (-6365 1955);
WIRE 16 -1 (-2275 4000)(-3050 4000);
FORCEPROP 2 LAST SIG_NAME CPU0_HDT_BYPASS_SEL
J 0
(-2875 4010);
DISPLAY 0.489362 (-2875 4010);
WIRE 16 -1 (-4100 4450)(-3250 4450);
FORCEPROP 2 LAST SIG_NAME CPU1_JTAG_BUF_R_OE
J 0
(-3985 4460);
DISPLAY 0.489362 (-3985 4460);
FORCEPROP 2 LASTPROP $XRERR UNIQUE?
J 0
(-4225 4460);
DISPLAY 0.638298 (-4225 4460);
PAINT MONO (-4225 4460);
DISPLAY INVISIBLE (-4225 4460);
WIRE 16 -1 (-4100 4050)(-3250 4050);
FORCEPROP 2 LAST SIG_NAME FM_SPD_CPU0_SWITCH_CTRL_R_N
J 0
(-3985 4060);
DISPLAY 0.489362 (-3985 4060);
FORCEPROP 2 LASTPROP $XRERR UNIQUE?
J 0
(-4225 4060);
DISPLAY 0.638298 (-4225 4060);
PAINT MONO (-4225 4060);
DISPLAY INVISIBLE (-4225 4060);
WIRE 16 -1 (-1425 2400)(-3550 2400);
FORCEPROP 2 LAST SIG_NAME SW_P12V_FAN_DR_EN
J 0
(-3375 2405);
DISPLAY 0.489362 (-3375 2405);
WIRE 16 -1 (-3550 1600)(-1425 1600);
FORCEPROP 2 LAST SIG_NAME FM_LED_D4
J 0
(-3385 1610);
DISPLAY 0.446809 (-3385 1610);
WIRE 16 -1 (-3550 1350)(-1425 1350);
FORCEPROP 2 LAST SIG_NAME FM_LED_D7
J 0
(-3385 1360);
DISPLAY 0.446809 (-3385 1360);
WIRE 16 -1 (-1425 1300)(-2450 1300);
FORCEPROP 2 LAST SIG_NAME RST_PERST_M2_2_N
J 0
(-2130 1310);
DISPLAY 0.489362 (-2130 1310);
WIRE 16 -1 (-3550 1250)(-1425 1250);
FORCEPROP 2 LAST SIG_NAME RST_PERST_OCP_SFF_N
J 0
(-3375 1255);
DISPLAY 0.489362 (-3375 1255);
WIRE 16 -1 (-3550 1000)(-1450 1000);
FORCEPROP 2 LAST SIG_NAME PRSNT_HDT_N
J 0
(-3375 1010);
DISPLAY 0.489362 (-3375 1010);
WIRE 16 -1 (-1425 800)(-3550 800);
FORCEPROP 0 LAST CDS_PHYS_NET_NAME SPI_PLD_CS_N
J 2
(-1700 850);
PAINT MONO (-1700 850);
DISPLAY INVISIBLE (-1700 850);
FORCEPROP 2 LAST SIG_NAME SPI_PLD_CS_N
J 0
(-2130 810);
DISPLAY 0.489362 (-2130 810);
WIRE 16 -1 (-1425 750)(-3550 750);
FORCEPROP 0 LAST CDS_PHYS_NET_NAME SPI_PLD_D0
J 2
(-1700 800);
PAINT MONO (-1700 800);
DISPLAY INVISIBLE (-1700 800);
FORCEPROP 2 LAST SIG_NAME SPI_PLD_D0
J 0
(-2130 760);
DISPLAY 0.489362 (-2130 760);
WIRE 16 -1 (-6400 700)(-5300 700);
FORCEPROP 2 LAST SIG_NAME P12V_E1S_2_EN
J 0
(-6125 710);
DISPLAY 0.489362 (-6125 710);
FORCEPROP 2 LASTPROP $XRERR UNIQUE?
J 0
(-6365 710);
DISPLAY 0.638298 (-6365 710);
PAINT MONO (-6365 710);
DISPLAY INVISIBLE (-6365 710);
WIRE 16 -1 (-6400 750)(-5300 750);
FORCEPROP 2 LAST SIG_NAME P12V_E1S_1_EN
J 0
(-6125 760);
DISPLAY 0.489362 (-6125 760);
FORCEPROP 2 LASTPROP $XRERR UNIQUE?
J 0
(-6365 760);
DISPLAY 0.638298 (-6365 760);
PAINT MONO (-6365 760);
DISPLAY INVISIBLE (-6365 760);
WIRE 16 -1 (-7425 800)(-5300 800);
FORCEPROP 2 LAST SIG_NAME PWGD_P3V3_E1S_1
J 0
(-7300 810);
DISPLAY 0.489362 (-7300 810);
WIRE 16 -1 (-5300 850)(-6400 850);
FORCEPROP 0 LAST SIG_NAME FM_E1S_2_R_PWRDIS
J 0
(-6125 860);
DISPLAY 0.489362 (-6125 860);
FORCEPROP 2 LASTPROP $XRERR UNIQUE?
J 0
(-6365 860);
DISPLAY 0.638298 (-6365 860);
PAINT MONO (-6365 860);
DISPLAY INVISIBLE (-6365 860);
WIRE 16 -1 (-5300 900)(-7425 900);
FORCEPROP 2 LAST SIG_NAME BMC_HPM_FPGA_LED1
J 0
(-6125 910);
DISPLAY 0.489362 (-6125 910);
WIRE 16 -1 (-6600 850)(-7425 850);
FORCEPROP 0 LAST SIG_NAME FM_E1S_2_PWRDIS
J 0
(-7300 860);
DISPLAY 0.489362 (-7300 860);
WIRE 16 -1 (-5300 2300)(-6400 2300);
FORCEPROP 2 LAST SIG_NAME FM_PWRGD_PVDDCR_CPU0_P1
J 0
(-6125 2305);
DISPLAY 0.489362 (-6125 2305);
FORCEPROP 2 LASTPROP $XRERR UNIQUE?
J 0
(-6365 2305);
DISPLAY 0.638298 (-6365 2305);
PAINT MONO (-6365 2305);
DISPLAY INVISIBLE (-6365 2305);
WIRE 16 -1 (-5300 2750)(-7425 2750);
FORCEPROP 2 LAST SIG_NAME PVDDCR_CPU0_P0_PMALERT
J 0
(-7300 2760);
DISPLAY 0.489362 (-7300 2760);
WIRE 16 -1 (-7425 3000)(-6600 3000);
FORCEPROP 2 LAST SIG_NAME PRSNT1_SLOT1_N
J 0
(-7300 3010);
DISPLAY 0.489362 (-7300 3010);
WIRE 16 -1 (-2275 4050)(-3050 4050);
FORCEPROP 2 LAST SIG_NAME FM_SPD_CPU0_SWITCH_CTRL_N
J 0
(-2875 4060);
DISPLAY 0.489362 (-2875 4060);
WIRE 16 -1 (-5400 3700)(-7225 3700);
FORCEPROP 2 LAST SIG_NAME FM_FAN_DR_FULL_SPEED
J 0
(-7050 3710);
DISPLAY 0.489362 (-7050 3710);
WIRE 16 -1 (-5400 3750)(-7225 3750);
FORCEPROP 2 LAST SIG_NAME FM_FAN_SR_FULL_SPEED
J 0
(-7050 3760);
DISPLAY 0.489362 (-7050 3760);
WIRE 16 -1 (-7225 3800)(-5400 3800);
FORCEPROP 2 LAST SIG_NAME CHASSIS_LEAK2_BUF_R
J 0
(-7050 3810);
DISPLAY 0.489362 (-7050 3810);
WIRE 16 -1 (-5400 3850)(-7225 3850);
FORCEPROP 2 LAST SIG_NAME HSC_GPIO2_PLD_N
J 0
(-7050 3860);
DISPLAY 0.489362 (-7050 3860);
WIRE 16 -1 (-7425 2600)(-5300 2600);
FORCEPROP 2 LAST SIG_NAME PMDU_NODE_ID0
J 0
(-6125 2610);
DISPLAY 0.489362 (-6125 2610);
WIRE 16 -1 (-7225 3900)(-5400 3900);
FORCEPROP 2 LAST SIG_NAME HSC_GPIO1_PLD_N
J 0
(-7050 3910);
DISPLAY 0.489362 (-7050 3910);
WIRE 16 -1 (-7425 2800)(-5300 2800);
FORCEPROP 2 LAST SIG_NAME PRSNT_OCP_N
J 0
(-7300 2810);
DISPLAY 0.489362 (-7300 2810);
WIRE 16 -1 (-6400 400)(-5300 400);
FORCEPROP 2 LAST SIG_NAME P3V3_E1S_1_EN
J 0
(-6125 410);
DISPLAY 0.489362 (-6125 410);
FORCEPROP 2 LASTPROP $XRERR UNIQUE?
J 0
(-6365 410);
DISPLAY 0.638298 (-6365 410);
PAINT MONO (-6365 410);
DISPLAY INVISIBLE (-6365 410);
WIRE 16 -1 (-5300 450)(-6400 450);
FORCEPROP 0 LAST SIG_NAME FM_E1S_1_R_PWRDIS
J 0
(-6125 460);
DISPLAY 0.489362 (-6125 460);
FORCEPROP 2 LASTPROP $XRERR UNIQUE?
J 0
(-6365 460);
DISPLAY 0.638298 (-6365 460);
PAINT MONO (-6365 460);
DISPLAY INVISIBLE (-6365 460);
WIRE 16 -1 (-5300 500)(-7425 500);
FORCEPROP 2 LAST SIG_NAME SW_P12V_FAN_SR_EN
J 0
(-7300 505);
DISPLAY 0.489362 (-7300 505);
WIRE 16 -1 (-7400 550)(-5300 550);
FORCEPROP 2 LAST SIG_NAME PWGD_P3V3_E1S_3
J 0
(-7300 560);
DISPLAY 0.489362 (-7300 560);
WIRE 16 -1 (-7425 600)(-5300 600);
FORCEPROP 2 LAST SIG_NAME P12V_E1S_3_PWRGD
J 0
(-7300 610);
DISPLAY 0.489362 (-7300 610);
WIRE 16 -1 (-5300 2500)(-6400 2500);
FORCEPROP 2 LAST SIG_NAME FM_UART_LS_EN
J 0
(-6135 2510);
DISPLAY 0.446809 (-6135 2510);
FORCEPROP 2 LASTPROP $XRERR UNIQUE?
J 0
(-6375 2510);
DISPLAY 0.638298 (-6375 2510);
PAINT MONO (-6375 2510);
DISPLAY INVISIBLE (-6375 2510);
WIRE 16 -1 (-5400 4600)(-6250 4600);
FORCEPROP 2 LAST SIG_NAME FM_CPU0_NMI_SYNC_FLOOD_N
J 0
(-6100 4610);
DISPLAY 0.489362 (-6100 4610);
FORCEPROP 2 LASTPROP $XRERR UNIQUE?
J 0
(-6340 4610);
DISPLAY 0.638298 (-6340 4610);
PAINT MONO (-6340 4610);
DISPLAY INVISIBLE (-6340 4610);
WIRE 16 -1 (-5400 4350)(-6250 4350);
FORCEPROP 2 LAST SIG_NAME FM_CPU0_PWR_BTN_N
J 0
(-6100 4360);
DISPLAY 0.489362 (-6100 4360);
FORCEPROP 2 LASTPROP $XRERR UNIQUE?
J 0
(-6340 4360);
DISPLAY 0.638298 (-6340 4360);
PAINT MONO (-6340 4360);
DISPLAY INVISIBLE (-6340 4360);
WIRE 16 -1 (-5400 4300)(-6250 4300);
FORCEPROP 2 LAST SIG_NAME FM_P1_PCC1_R_N
J 0
(-6100 4310);
DISPLAY 0.489362 (-6100 4310);
FORCEPROP 2 LASTPROP $XRERR UNIQUE?
J 0
(-6340 4310);
DISPLAY 0.638298 (-6340 4310);
PAINT MONO (-6340 4310);
DISPLAY INVISIBLE (-6340 4310);
WIRE 16 -1 (-7225 4250)(-5400 4250);
FORCEPROP 0 LAST SIG_NAME FM_FAN_DR_FAIL_N
J 0
(-7050 4260);
DISPLAY 0.489362 (-7050 4260);
WIRE 16 -1 (-7225 4200)(-5400 4200);
FORCEPROP 0 LAST SIG_NAME FM_FAN_SR_FAIL_N
J 0
(-7050 4210);
DISPLAY 0.489362 (-7050 4210);
WIRE 16 -1 (-5400 4150)(-6250 4150);
FORCEPROP 2 LAST SIG_NAME FM_P0_PCC1_R_N
J 0
(-6100 4160);
DISPLAY 0.489362 (-6100 4160);
FORCEPROP 2 LASTPROP $XRERR UNIQUE?
J 0
(-6340 4160);
DISPLAY 0.638298 (-6340 4160);
PAINT MONO (-6340 4160);
DISPLAY INVISIBLE (-6340 4160);
WIRE 16 -1 (-5400 4100)(-6250 4100);
FORCEPROP 2 LAST SIG_NAME FM_P0_PCC0_R_N
J 0
(-6100 4110);
DISPLAY 0.489362 (-6100 4110);
FORCEPROP 2 LASTPROP $XRERR UNIQUE?
J 0
(-6340 4110);
DISPLAY 0.638298 (-6340 4110);
PAINT MONO (-6340 4110);
DISPLAY INVISIBLE (-6340 4110);
WIRE 16 -1 (-7225 4050)(-5400 4050);
FORCEPROP 2 LAST SIG_NAME APML_CPU1_ALERT_R_N
J 0
(-7050 4060);
DISPLAY 0.489362 (-7050 4060);
WIRE 16 -1 (-7225 4000)(-5400 4000);
FORCEPROP 2 LAST SIG_NAME APML_CPU0_ALERT_R_N
J 0
(-7050 4010);
DISPLAY 0.489362 (-7050 4010);
WIRE 16 -1 (-5400 3950)(-6250 3950);
FORCEPROP 2 LAST SIG_NAME CPU1_SPD_HOST_CTRL_R1_N
J 0
(-6100 3960);
DISPLAY 0.489362 (-6100 3960);
FORCEPROP 2 LASTPROP $XRERR UNIQUE?
J 0
(-6340 3960);
DISPLAY 0.638298 (-6340 3960);
PAINT MONO (-6340 3960);
DISPLAY INVISIBLE (-6340 3960);
WIRE 16 -1 (-6600 700)(-7425 700);
FORCEPROP 2 LAST SIG_NAME P12V_E1S_2_EN_R
J 0
(-7300 710);
DISPLAY 0.489362 (-7300 710);
WIRE 16 -1 (-6600 450)(-7425 450);
FORCEPROP 0 LAST SIG_NAME FM_E1S_1_PWRDIS
J 0
(-7300 460);
DISPLAY 0.489362 (-7300 460);
WIRE 16 -1 (-6600 400)(-7425 400);
FORCEPROP 2 LAST SIG_NAME P3V3_E1S_1_EN_R
J 0
(-7300 410);
DISPLAY 0.489362 (-7300 410);
WIRE 16 -1 (-7425 2550)(-5300 2550);
FORCEPROP 2 LAST SIG_NAME SLOT2_SKU_ID1
J 0
(-6125 2560);
DISPLAY 0.489362 (-6125 2560);
WIRE 16 -1 (-5300 2850)(-6400 2850);
FORCEPROP 2 LAST SIG_NAME FM_PWRGD_PVDDIO_P0
J 0
(-6125 2855);
DISPLAY 0.489362 (-6125 2855);
FORCEPROP 2 LASTPROP $XRERR UNIQUE?
J 0
(-6365 2855);
DISPLAY 0.638298 (-6365 2855);
PAINT MONO (-6365 2855);
DISPLAY INVISIBLE (-6365 2855);
WIRE 16 -1 (-3250 4650)(-4100 4650);
FORCEPROP 2 LAST SIG_NAME SCM_USB_OC_R_N
J 0
(-3985 4660);
DISPLAY 0.489362 (-3985 4660);
FORCEPROP 2 LASTPROP $XRERR UNIQUE?
J 0
(-4225 4660);
DISPLAY 0.638298 (-4225 4660);
PAINT MONO (-4225 4660);
DISPLAY INVISIBLE (-4225 4660);
WIRE 16 -1 (-3550 1550)(-1425 1550);
FORCEPROP 2 LAST SIG_NAME FM_LED_D5
J 0
(-3385 1560);
DISPLAY 0.446809 (-3385 1560);
WIRE 16 -1 (-1425 1500)(-3550 1500);
FORCEPROP 2 LAST SIG_NAME SW_P3V3_EN
J 0
(-3375 1505);
DISPLAY 0.489362 (-3375 1505);
WIRE 16 -1 (-3550 2550)(-2650 2550);
FORCEPROP 2 LAST SIG_NAME RST_PERST_E1S_1_R_N
J 0
(-3375 2555);
DISPLAY 0.489362 (-3375 2555);
FORCEPROP 2 LASTPROP $XRERR UNIQUE?
J 0
(-3615 2555);
DISPLAY 0.638298 (-3615 2555);
PAINT MONO (-3615 2555);
DISPLAY INVISIBLE (-3615 2555);
WIRE 16 -1 (-3550 2600)(-2650 2600);
FORCEPROP 2 LAST SIG_NAME FM_RST_PERST_SCM_R_N
J 0
(-3375 2605);
DISPLAY 0.489362 (-3375 2605);
FORCEPROP 2 LASTPROP $XRERR UNIQUE?
J 0
(-3615 2605);
DISPLAY 0.638298 (-3615 2605);
PAINT MONO (-3615 2605);
DISPLAY INVISIBLE (-3615 2605);
WIRE 16 -1 (-3550 2650)(-2650 2650);
FORCEPROP 2 LAST SIG_NAME PRSNT2_SLOT2_R_N
J 0
(-3385 2660);
DISPLAY 0.446809 (-3385 2660);
FORCEPROP 2 LASTPROP $XRERR UNIQUE?
J 0
(-3625 2660);
DISPLAY 0.638298 (-3625 2660);
PAINT MONO (-3625 2660);
DISPLAY INVISIBLE (-3625 2660);
WIRE 16 -1 (-3550 2750)(-2650 2750);
FORCEPROP 2 LAST SIG_NAME PSU1_PS_ON_R_N
J 0
(-3375 2755);
DISPLAY 0.489362 (-3375 2755);
FORCEPROP 2 LASTPROP $XRERR UNIQUE?
J 0
(-3615 2755);
DISPLAY 0.638298 (-3615 2755);
PAINT MONO (-3615 2755);
DISPLAY INVISIBLE (-3615 2755);
WIRE 16 -1 (-3550 2800)(-2650 2800);
FORCEPROP 2 LAST SIG_NAME PRSNT2_SLOT1_R_N
J 0
(-3385 2810);
DISPLAY 0.446809 (-3385 2810);
FORCEPROP 2 LASTPROP $XRERR UNIQUE?
J 0
(-3625 2810);
DISPLAY 0.638298 (-3625 2810);
PAINT MONO (-3625 2810);
DISPLAY INVISIBLE (-3625 2810);
WIRE 16 -1 (-3550 2700)(-2650 2700);
FORCEPROP 2 LAST SIG_NAME P3V3_E1S_2_EN
J 0
(-3375 2710);
DISPLAY 0.489362 (-3375 2710);
FORCEPROP 2 LASTPROP $XRERR UNIQUE?
J 0
(-3615 2710);
DISPLAY 0.638298 (-3615 2710);
PAINT MONO (-3615 2710);
DISPLAY INVISIBLE (-3615 2710);
WIRE 16 -1 (-5300 2650)(-6400 2650);
FORCEPROP 2 LAST SIG_NAME FM_PVDDCR_CPU0_P1_R_EN
J 0
(-6125 2655);
DISPLAY 0.489362 (-6125 2655);
FORCEPROP 2 LASTPROP $XRERR UNIQUE?
J 0
(-6365 2655);
DISPLAY 0.638298 (-6365 2655);
PAINT MONO (-6365 2655);
DISPLAY INVISIBLE (-6365 2655);
WIRE 16 -1 (-5300 2700)(-6400 2700);
FORCEPROP 2 LAST SIG_NAME FM_PWRGD_PVDD11_S3_P0
J 0
(-6125 2705);
DISPLAY 0.489362 (-6125 2705);
FORCEPROP 2 LASTPROP $XRERR UNIQUE?
J 0
(-6365 2705);
DISPLAY 0.638298 (-6365 2705);
PAINT MONO (-6365 2705);
DISPLAY INVISIBLE (-6365 2705);
WIRE 16 -1 (-5300 2900)(-6400 2900);
FORCEPROP 2 LAST SIG_NAME FM_PVDDIO_P0_EN
J 0
(-6125 2905);
DISPLAY 0.489362 (-6125 2905);
FORCEPROP 2 LASTPROP $XRERR UNIQUE?
J 0
(-6365 2905);
DISPLAY 0.638298 (-6365 2905);
PAINT MONO (-6365 2905);
DISPLAY INVISIBLE (-6365 2905);
WIRE 16 -1 (-6600 750)(-7425 750);
FORCEPROP 2 LAST SIG_NAME P12V_E1S_1_EN_R
J 0
(-7300 760);
DISPLAY 0.489362 (-7300 760);
WIRE 16 -1 (-3250 4500)(-4100 4500);
FORCEPROP 0 LAST CDS_PHYS_NET_NAME FM_PLD_CPU1_PRSNT_HDT
J 2
(-3525 4550);
PAINT MONO (-3525 4550);
DISPLAY INVISIBLE (-3525 4550);
FORCEPROP 2 LAST SIG_NAME FM_PLD_CPU1_PRSNT_HDT
J 0
(-3985 4510);
DISPLAY 0.489362 (-3985 4510);
FORCEPROP 2 LASTPROP $XRERR UNIQUE?
J 0
(-4225 4510);
DISPLAY 0.638298 (-4225 4510);
PAINT MONO (-4225 4510);
DISPLAY INVISIBLE (-4225 4510);
WIRE 16 -1 (-3050 4200)(-2275 4200);
FORCEPROP 2 LAST SIG_NAME BMC_JTAG_SEL
J 0
(-2875 4210);
DISPLAY 0.489362 (-2875 4210);
WIRE 16 -1 (-3050 4100)(-2275 4100);
FORCEPROP 2 LAST SIG_NAME ROM_SD_LS_OE
J 0
(-2885 4110);
DISPLAY 0.446809 (-2885 4110);
WIRE 16 -1 (-3050 4150)(-2275 4150);
FORCEPROP 2 LAST SIG_NAME ROM_LS_EN
J 0
(-2885 4160);
DISPLAY 0.446809 (-2885 4160);
WIRE 16 -1 (-3050 4550)(-2275 4550);
FORCEPROP 2 LAST SIG_NAME CPU0_SPD_HOST_CTRL_N
J 0
(-2875 4560);
DISPLAY 0.489362 (-2875 4560);
WIRE 16 -1 (-2275 4500)(-3050 4500);
FORCEPROP 2 LAST SIG_NAME CPU1_HDT_BYPASS_SEL
J 0
(-2875 4510);
DISPLAY 0.489362 (-2875 4510);
WIRE 16 -1 (-2275 4300)(-3050 4300);
FORCEPROP 2 LAST SIG_NAME P12V_ALL_PWROK
J 0
(-2875 4310);
DISPLAY 0.489362 (-2875 4310);
WIRE 16 -1 (-2275 4400)(-3050 4400);
FORCEPROP 2 LAST SIG_NAME SCM_IRQ_1V8_N
J 0
(-2875 4410);
DISPLAY 0.489362 (-2875 4410);
WIRE 16 -1 (-3050 4450)(-2275 4450);
FORCEPROP 2 LAST SIG_NAME CPU1_JTAG_BUF_OE
J 0
(-2875 4460);
DISPLAY 0.489362 (-2875 4460);
WIRE 16 -1 (-3250 4750)(-4100 4750);
FORCEPROP 2 LAST SIG_NAME FM_CPU1_NMI_SYNC_FLOOD_N
J 0
(-3985 4760);
DISPLAY 0.489362 (-3985 4760);
FORCEPROP 2 LASTPROP $XRERR UNIQUE?
J 0
(-4225 4760);
DISPLAY 0.638298 (-4225 4760);
PAINT MONO (-4225 4760);
DISPLAY INVISIBLE (-4225 4760);
WIRE 16 -1 (-2275 4650)(-3050 4650);
FORCEPROP 2 LAST SIG_NAME SCM_USB_OC_N
J 0
(-2875 4660);
DISPLAY 0.489362 (-2875 4660);
WIRE 16 -1 (-2275 4800)(-4100 4800);
FORCEPROP 2 LAST SIG_NAME FM_BIOS_USB_RECOVERY
J 0
(-3985 4810);
DISPLAY 0.489362 (-3985 4810);
WIRE 16 -1 (-3050 5300)(-2275 5300);
FORCEPROP 2 LAST SIG_NAME ESPI_CPU0_CS1_N
J 0
(-2885 5310);
DISPLAY 0.446809 (-2885 5310);
WIRE 16 -1 (-3050 5250)(-2275 5250);
FORCEPROP 2 LAST SIG_NAME ESPI_CPU0_ALERT_N
J 0
(-2885 5260);
DISPLAY 0.446809 (-2885 5260);
WIRE 16 -1 (-3050 5200)(-2275 5200);
FORCEPROP 2 LAST SIG_NAME RST_ESPI_CPU0_RSTOUT_N
J 0
(-2885 5210);
DISPLAY 0.446809 (-2885 5210);
WIRE 16 -1 (-3050 5150)(-2275 5150);
FORCEPROP 2 LAST SIG_NAME ESPI_CPU0_D0
J 0
(-2885 5160);
DISPLAY 0.446809 (-2885 5160);
WIRE 16 -1 (-3050 5100)(-2275 5100);
FORCEPROP 2 LAST SIG_NAME ESPI_CPU0_D1
J 0
(-2885 5110);
DISPLAY 0.446809 (-2885 5110);
WIRE 16 -1 (-3050 5050)(-2275 5050);
FORCEPROP 2 LAST SIG_NAME ESPI_CPU0_D2
J 0
(-2885 5060);
DISPLAY 0.446809 (-2885 5060);
WIRE 16 -1 (-5400 5050)(-7225 5050);
FORCEPROP 0 LAST SIG_NAME SMB_SLOT1_ALERT_R_N
J 0
(-6100 5060);
DISPLAY 0.489362 (-6100 5060);
WIRE 16 -1 (-7225 5100)(-5400 5100);
FORCEPROP 0 LAST SIG_NAME SLOT2_CLKREQ_1_R_N
J 0
(-7050 5110);
DISPLAY 0.489362 (-7050 5110);
WIRE 16 -1 (-6250 5150)(-5400 5150);
FORCEPROP 2 LAST SIG_NAME FM_CPU0_NV_SAVE_N
J 0
(-6100 5160);
DISPLAY 0.489362 (-6100 5160);
FORCEPROP 2 LASTPROP $XRERR UNIQUE?
J 0
(-6340 5160);
DISPLAY 0.638298 (-6340 5160);
PAINT MONO (-6340 5160);
DISPLAY INVISIBLE (-6340 5160);
WIRE 16 -1 (-6250 5200)(-5400 5200);
FORCEPROP 2 LAST SIG_NAME FM_CPU1_SYS_RESET_N
J 0
(-6100 5210);
DISPLAY 0.489362 (-6100 5210);
FORCEPROP 2 LASTPROP $XRERR UNIQUE?
J 0
(-6340 5210);
DISPLAY 0.638298 (-6340 5210);
PAINT MONO (-6340 5210);
DISPLAY INVISIBLE (-6340 5210);
WIRE 16 -1 (-5400 5250)(-6250 5250);
FORCEPROP 2 LAST SIG_NAME FM_CPU0_SYS_RESET_N
J 0
(-6100 5260);
DISPLAY 0.489362 (-6100 5260);
FORCEPROP 2 LASTPROP $XRERR UNIQUE?
J 0
(-6340 5260);
DISPLAY 0.638298 (-6340 5260);
PAINT MONO (-6340 5260);
DISPLAY INVISIBLE (-6340 5260);
WIRE 16 -1 (-7225 5300)(-5400 5300);
FORCEPROP 0 LAST SIG_NAME SLOT1_CLKREQ_0_R_N
J 0
(-7050 5310);
DISPLAY 0.489362 (-7050 5310);
WIRE 16 -1 (-6250 5350)(-5400 5350);
FORCEPROP 2 LAST SIG_NAME FM_CPU0_RSMRST_N
J 0
(-6100 5360);
DISPLAY 0.489362 (-6100 5360);
FORCEPROP 2 LASTPROP $XRERR UNIQUE?
J 0
(-6340 5360);
DISPLAY 0.638298 (-6340 5360);
PAINT MONO (-6340 5360);
DISPLAY INVISIBLE (-6340 5360);
WIRE 16 -1 (-7225 5450)(-5400 5450);
FORCEPROP 0 LAST SIG_NAME SLOT1_CLKREQ_1_R_N
J 0
(-7050 5460);
DISPLAY 0.489362 (-7050 5460);
WIRE 16 -1 (-5400 5500)(-6250 5500);
FORCEPROP 2 LAST SIG_NAME RST_CPU1_PERST0_R_N
J 0
(-6100 5510);
DISPLAY 0.489362 (-6100 5510);
FORCEPROP 2 LASTPROP $XRERR UNIQUE?
J 0
(-6340 5510);
DISPLAY 0.638298 (-6340 5510);
PAINT MONO (-6340 5510);
DISPLAY INVISIBLE (-6340 5510);
WIRE 16 -1 (-7225 5550)(-5400 5550);
FORCEPROP 2 LAST SIG_NAME CHASSIS_LEAK1_BUF_R
J 0
(-7050 5560);
DISPLAY 0.489362 (-7050 5560);
WIRE 16 -1 (-7225 5600)(-5400 5600);
FORCEPROP 2 LAST SIG_NAME CHASSIS_LEAK0_BUF_R
J 0
(-7050 5610);
DISPLAY 0.489362 (-7050 5610);
WIRE 16 -1 (-6250 5650)(-5400 5650);
FORCEPROP 2 LAST SIG_NAME RST_CPU0_PERST1_R_N
J 0
(-6100 5660);
DISPLAY 0.489362 (-6100 5660);
FORCEPROP 2 LASTPROP $XRERR UNIQUE?
J 0
(-6340 5660);
DISPLAY 0.638298 (-6340 5660);
PAINT MONO (-6340 5660);
DISPLAY INVISIBLE (-6340 5660);
WIRE 16 -1 (-5400 5700)(-7225 5700);
FORCEPROP 0 LAST SIG_NAME SMB_SLOT2_ALERT_R_N
J 0
(-6100 5710);
DISPLAY 0.489362 (-6100 5710);
WIRE 16 -1 (-7225 4400)(-5400 4400);
FORCEPROP 0 LAST SIG_NAME SLOT2_CLKREQ_0_R_N
J 0
(-7050 4410);
DISPLAY 0.489362 (-7050 4410);
WIRE 16 -1 (-5400 4900)(-6250 4900);
FORCEPROP 2 LAST SIG_NAME RST_CPU0_KBRST_N
J 0
(-6100 4910);
DISPLAY 0.489362 (-6100 4910);
FORCEPROP 2 LASTPROP $XRERR UNIQUE?
J 0
(-6340 4910);
DISPLAY 0.638298 (-6340 4910);
PAINT MONO (-6340 4910);
DISPLAY INVISIBLE (-6340 4910);
WIRE 16 -1 (-7225 5750)(-5400 5750);
FORCEPROP 2 LAST SIG_NAME FM_CPU1_SLP_S3_N
J 0
(-7050 5760);
DISPLAY 0.489362 (-7050 5760);
WIRE 16 -1 (-7225 5800)(-5400 5800);
FORCEPROP 2 LAST SIG_NAME FM_CPU1_SLP_S5_N
J 0
(-7050 5810);
DISPLAY 0.489362 (-7050 5810);
WIRE 16 -1 (-5400 5850)(-6250 5850);
FORCEPROP 2 LAST SIG_NAME RST_CPU1_PERST1_R_N
J 0
(-6100 5860);
DISPLAY 0.489362 (-6100 5860);
FORCEPROP 2 LASTPROP $XRERR UNIQUE?
J 0
(-6340 5860);
DISPLAY 0.638298 (-6340 5860);
PAINT MONO (-6340 5860);
DISPLAY INVISIBLE (-6340 5860);
WIRE 16 -1 (-6250 5900)(-5400 5900);
FORCEPROP 2 LAST SIG_NAME RST_CPU0_PERST0_R_N
J 0
(-6100 5910);
DISPLAY 0.489362 (-6100 5910);
FORCEPROP 2 LASTPROP $XRERR UNIQUE?
J 0
(-6340 5910);
DISPLAY 0.638298 (-6340 5910);
PAINT MONO (-6340 5910);
DISPLAY INVISIBLE (-6340 5910);
WIRE 16 -1 (-7225 5950)(-5400 5950);
FORCEPROP 2 LAST SIG_NAME FM_CPU0_SLP_S3_N
J 0
(-7050 5960);
DISPLAY 0.489362 (-7050 5960);
WIRE 16 -1 (-5400 5400)(-6250 5400);
FORCEPROP 2 LAST SIG_NAME FM_CPU1_RSMRST_N
J 0
(-6100 5410);
DISPLAY 0.489362 (-6100 5410);
FORCEPROP 2 LASTPROP $XRERR UNIQUE?
J 0
(-6340 5410);
DISPLAY 0.638298 (-6340 5410);
PAINT MONO (-6340 5410);
DISPLAY INVISIBLE (-6340 5410);
WIRE 16 -1 (-6250 5000)(-5400 5000);
FORCEPROP 2 LAST SIG_NAME FM_RST_CPU0_RESETL_N
J 0
(-6100 5010);
DISPLAY 0.489362 (-6100 5010);
FORCEPROP 2 LASTPROP $XRERR UNIQUE?
J 0
(-6340 5010);
DISPLAY 0.638298 (-6340 5010);
PAINT MONO (-6340 5010);
DISPLAY INVISIBLE (-6340 5010);
WIRE 16 -1 (-6250 4950)(-5400 4950);
FORCEPROP 2 LAST SIG_NAME FM_RST_CPU1_RESETL_N
J 0
(-6100 4960);
DISPLAY 0.489362 (-6100 4960);
FORCEPROP 2 LASTPROP $XRERR UNIQUE?
J 0
(-6340 4960);
DISPLAY 0.638298 (-6340 4960);
PAINT MONO (-6340 4960);
DISPLAY INVISIBLE (-6340 4960);
WIRE 16 -1 (-4100 5200)(-3250 5200);
FORCEPROP 2 LAST SIG_NAME RST_ESPI_CPU0_RSTOUT_R_N
J 0
(-3985 5210);
DISPLAY 0.446809 (-3985 5210);
FORCEPROP 2 LASTPROP $XRERR UNIQUE?
J 0
(-4225 5210);
DISPLAY 0.638298 (-4225 5210);
PAINT MONO (-4225 5210);
DISPLAY INVISIBLE (-4225 5210);
WIRE 16 -1 (-4100 5700)(-2275 5700);
FORCEPROP 2 LAST SIG_NAME P12V_SCM_PWRGD
J 0
(-3985 5710);
DISPLAY 0.489362 (-3985 5710);
WIRE 16 -1 (-4100 4700)(-2275 4700);
FORCEPROP 2 LAST SIG_NAME WC_PRSNT_1_N
J 0
(-2875 4710);
DISPLAY 0.489362 (-2875 4710);
WIRE 16 -1 (-4100 4550)(-3250 4550);
FORCEPROP 2 LAST SIG_NAME CPU0_SPD_HOST_CTRL_R1_N
J 0
(-3985 4560);
DISPLAY 0.489362 (-3985 4560);
FORCEPROP 2 LASTPROP $XRERR UNIQUE?
J 0
(-4225 4560);
DISPLAY 0.638298 (-4225 4560);
PAINT MONO (-4225 4560);
DISPLAY INVISIBLE (-4225 4560);
WIRE 16 -1 (-1425 1700)(-2450 1700);
FORCEPROP 2 LAST SIG_NAME RST_PERST_E1S_4_N
J 0
(-2130 1710);
DISPLAY 0.489362 (-2130 1710);
WIRE 16 -1 (-1425 1650)(-2450 1650);
FORCEPROP 2 LAST SIG_NAME RST_PERST_SLOT2_0_N
J 0
(-2130 1660);
DISPLAY 0.489362 (-2130 1660);
WIRE 16 -1 (-1425 1450)(-2450 1450);
FORCEPROP 2 LAST SIG_NAME RST_PERST_M2_1_N
J 0
(-2130 1460);
DISPLAY 0.489362 (-2130 1460);
WIRE 16 -1 (-3550 2200)(-2650 2200);
FORCEPROP 2 LAST SIG_NAME RST_SMBMUX_U7_R_N
J 0
(-3375 2205);
DISPLAY 0.489362 (-3375 2205);
FORCEPROP 2 LASTPROP $XRERR UNIQUE?
J 0
(-3615 2205);
DISPLAY 0.638298 (-3615 2205);
PAINT MONO (-3615 2205);
DISPLAY INVISIBLE (-3615 2205);
WIRE 16 -1 (-2650 1650)(-3550 1650);
FORCEPROP 2 LAST SIG_NAME RST_PERST_SLOT2_0_R_N
J 0
(-3375 1655);
DISPLAY 0.489362 (-3375 1655);
FORCEPROP 2 LASTPROP $XRERR UNIQUE?
J 0
(-3615 1655);
DISPLAY 0.638298 (-3615 1655);
PAINT MONO (-3615 1655);
DISPLAY INVISIBLE (-3615 1655);
WIRE 16 -1 (-3550 1400)(-1425 1400);
FORCEPROP 2 LAST SIG_NAME FM_LED_D6
J 0
(-3385 1410);
DISPLAY 0.446809 (-3385 1410);
WIRE 16 -1 (-6600 1700)(-7425 1700);
FORCEPROP 2 LAST SIG_NAME PVDD33_S5_EN
J 0
(-7300 1710);
DISPLAY 0.489362 (-7300 1710);
WIRE 16 -1 (-3050 5350)(-2275 5350);
FORCEPROP 2 LAST SIG_NAME CLK_ESPI_CPU0_CLK1
J 0
(-2885 5360);
DISPLAY 0.446809 (-2885 5360);
WIRE 16 -1 (-3250 5550)(-4100 5550);
FORCEPROP 2 LAST SIG_NAME FM_CPU0_HDT_CONN_TESTEN
J 0
(-3985 5560);
DISPLAY 0.489362 (-3985 5560);
FORCEPROP 2 LASTPROP $XRERR UNIQUE?
J 0
(-4225 5560);
DISPLAY 0.638298 (-4225 5560);
PAINT MONO (-4225 5560);
DISPLAY INVISIBLE (-4225 5560);
WIRE 16 -1 (-4100 5500)(-2275 5500);
FORCEPROP 2 LAST SIG_NAME PWRGD_P12V_FAN_DR_R
J 0
(-3985 5510);
DISPLAY 0.489362 (-3985 5510);
WIRE 16 -1 (-4100 5450)(-2275 5450);
FORCEPROP 2 LAST SIG_NAME PWRGD_P12V_MEM_R
J 0
(-3985 5460);
DISPLAY 0.489362 (-3985 5460);
WIRE 16 -1 (-4100 5400)(-2275 5400);
FORCEPROP 2 LAST SIG_NAME FM_JTAG_BMC_OE
J 0
(-2885 5410);
DISPLAY 0.489362 (-2885 5410);
WIRE 16 -1 (-2275 5550)(-3050 5550);
FORCEPROP 2 LAST SIG_NAME CPU0_HDT_CONN_TESTEN
J 0
(-2875 5560);
DISPLAY 0.489362 (-2875 5560);
WIRE 16 -1 (-4100 5350)(-3250 5350);
FORCEPROP 2 LAST SIG_NAME CLK_ESPI_CPU0_R1_CLK1
J 0
(-3985 5360);
DISPLAY 0.446809 (-3985 5360);
FORCEPROP 2 LASTPROP $XRERR UNIQUE?
J 0
(-4225 5360);
DISPLAY 0.638298 (-4225 5360);
PAINT MONO (-4225 5360);
DISPLAY INVISIBLE (-4225 5360);
WIRE 16 -1 (-4100 5300)(-3250 5300);
FORCEPROP 2 LAST SIG_NAME ESPI_CPU0_CS1_R_N
J 0
(-3985 5310);
DISPLAY 0.446809 (-3985 5310);
FORCEPROP 2 LASTPROP $XRERR UNIQUE?
J 0
(-4225 5310);
DISPLAY 0.638298 (-4225 5310);
PAINT MONO (-4225 5310);
DISPLAY INVISIBLE (-4225 5310);
WIRE 16 -1 (-4100 5250)(-3250 5250);
FORCEPROP 2 LAST SIG_NAME ESPI_CPU0_ALERT_R_N
J 0
(-3985 5260);
DISPLAY 0.446809 (-3985 5260);
FORCEPROP 2 LASTPROP $XRERR UNIQUE?
J 0
(-4225 5260);
DISPLAY 0.638298 (-4225 5260);
PAINT MONO (-4225 5260);
DISPLAY INVISIBLE (-4225 5260);
WIRE 16 -1 (-2275 5750)(-3050 5750);
FORCEPROP 2 LAST SIG_NAME CPU1_SMERR_N
J 0
(-2875 5760);
DISPLAY 0.489362 (-2875 5760);
WIRE 16 -1 (-4100 5900)(-2275 5900);
FORCEPROP 2 LAST SIG_NAME SMB_CPU_5_R1_SCL
J 0
(-3985 5910);
DISPLAY 0.489362 (-3985 5910);
WIRE 16 -1 (-4100 5850)(-2275 5850);
FORCEPROP 2 LAST SIG_NAME SMB_CPU_5_R1_SDA
J 0
(-3985 5860);
DISPLAY 0.489362 (-3985 5860);
WIRE 16 -1 (-4100 4850)(-3250 4850);
FORCEPROP 2 LAST SIG_NAME FM_BIOS_POST_CMPLT_BUF_R_N
J 0
(-3985 4860);
DISPLAY 0.489362 (-3985 4860);
FORCEPROP 2 LASTPROP $XRERR UNIQUE?
J 0
(-4225 4860);
DISPLAY 0.638298 (-4225 4860);
PAINT MONO (-4225 4860);
DISPLAY INVISIBLE (-4225 4860);
WIRE 16 -1 (-4100 5150)(-3250 5150);
FORCEPROP 2 LAST SIG_NAME ESPI_CPU0_R1_D0
J 0
(-3985 5160);
DISPLAY 0.446809 (-3985 5160);
FORCEPROP 2 LASTPROP $XRERR UNIQUE?
J 0
(-4225 5160);
DISPLAY 0.638298 (-4225 5160);
PAINT MONO (-4225 5160);
DISPLAY INVISIBLE (-4225 5160);
WIRE 16 -1 (-3250 5750)(-4100 5750);
FORCEPROP 2 LAST SIG_NAME FM_CPU1_SMERR_N
J 0
(-3985 5760);
DISPLAY 0.489362 (-3985 5760);
FORCEPROP 2 LASTPROP $XRERR UNIQUE?
J 0
(-4225 5760);
DISPLAY 0.638298 (-4225 5760);
PAINT MONO (-4225 5760);
DISPLAY INVISIBLE (-4225 5760);
WIRE 16 -1 (-4100 6000)(-3250 6000);
FORCEPROP 2 LAST SIG_NAME FM_SMERR_LED_R_N
J 0
(-3985 6010);
DISPLAY 0.489362 (-3985 6010);
FORCEPROP 2 LASTPROP $XRERR UNIQUE?
J 0
(-4225 6010);
DISPLAY 0.638298 (-4225 6010);
PAINT MONO (-4225 6010);
DISPLAY INVISIBLE (-4225 6010);
WIRE 16 -1 (-4100 5950)(-3250 5950);
FORCEPROP 2 LAST SIG_NAME FM_CPU0_SMERR_N
J 0
(-3985 5960);
DISPLAY 0.489362 (-3985 5960);
FORCEPROP 2 LASTPROP $XRERR UNIQUE?
J 0
(-4225 5960);
DISPLAY 0.638298 (-4225 5960);
PAINT MONO (-4225 5960);
DISPLAY INVISIBLE (-4225 5960);
WIRE 16 -1 (-4100 5800)(-2275 5800);
FORCEPROP 2 LAST SIG_NAME PWRGD_P3V3_R
J 0
(-3985 5810);
DISPLAY 0.489362 (-3985 5810);
WIRE 16 -1 (-4100 5650)(-2275 5650);
FORCEPROP 2 LAST SIG_NAME PWRGD_P12V_R
J 0
(-3985 5660);
DISPLAY 0.489362 (-3985 5660);
WIRE 16 -1 (-5400 4850)(-6250 4850);
FORCEPROP 2 LAST SIG_NAME CPU0_JTAG_BUF_R_OE
J 0
(-6110 4860);
DISPLAY 0.446809 (-6110 4860);
FORCEPROP 2 LASTPROP $XRERR UNIQUE?
J 0
(-6350 4860);
DISPLAY 0.638298 (-6350 4860);
PAINT MONO (-6350 4860);
DISPLAY INVISIBLE (-6350 4860);
WIRE 16 -1 (-6250 4800)(-5400 4800);
FORCEPROP 2 LAST SIG_NAME FM_PWRGD_CPU0_PWROK
J 0
(-6100 4810);
DISPLAY 0.489362 (-6100 4810);
FORCEPROP 2 LASTPROP $XRERR UNIQUE?
J 0
(-6340 4810);
DISPLAY 0.638298 (-6340 4810);
PAINT MONO (-6340 4810);
DISPLAY INVISIBLE (-6340 4810);
WIRE 16 -1 (-5400 4700)(-7225 4700);
FORCEPROP 2 LAST SIG_NAME PVDD11_S3_P0_RESET_N
J 0
(-7050 4710);
DISPLAY 0.489362 (-7050 4710);
WIRE 16 -1 (-2275 4750)(-3050 4750);
FORCEPROP 2 LAST SIG_NAME CPU1_NMI_SYNC_FLOOD_N
J 0
(-2875 4760);
DISPLAY 0.489362 (-2875 4760);
WIRE 16 -1 (-3050 4850)(-2275 4850);
FORCEPROP 2 LAST SIG_NAME FM_BIOS_POST_CMPLT_BUF_N
J 0
(-2875 4860);
DISPLAY 0.489362 (-2875 4860);
WIRE 16 -1 (-3050 4900)(-2275 4900);
FORCEPROP 2 LAST SIG_NAME HDT_HDR_RESET_N
J 0
(-2875 4910);
DISPLAY 0.489362 (-2875 4910);
WIRE 16 -1 (-3050 4950)(-2275 4950);
FORCEPROP 2 LAST SIG_NAME HDT_HDR_PWROK
J 0
(-2875 4960);
DISPLAY 0.489362 (-2875 4960);
WIRE 16 -1 (-3050 5000)(-2275 5000);
FORCEPROP 2 LAST SIG_NAME ESPI_CPU0_D3
J 0
(-2885 5010);
DISPLAY 0.446809 (-2885 5010);
WIRE 16 -1 (-7450 2350)(-5300 2350);
FORCEPROP 2 LAST SIG_NAME FM_LED_D1
J 0
(-7310 2360);
DISPLAY 0.446809 (-7310 2360);
WIRE 16 -1 (-5300 2450)(-6400 2450);
FORCEPROP 2 LAST SIG_NAME FM_PWRGD_PVDDCR_CPU1_P1
J 0
(-6125 2455);
DISPLAY 0.489362 (-6125 2455);
FORCEPROP 2 LASTPROP $XRERR UNIQUE?
J 0
(-6365 2455);
DISPLAY 0.638298 (-6365 2455);
PAINT MONO (-6365 2455);
DISPLAY INVISIBLE (-6365 2455);
WIRE 16 -1 (-6600 2700)(-7425 2700);
FORCEPROP 2 LAST SIG_NAME PWRGD_PVDD11_S3_P0
J 0
(-7300 2710);
DISPLAY 0.489362 (-7300 2710);
WIRE 16 -1 (-6600 2650)(-7425 2650);
FORCEPROP 2 LAST SIG_NAME PVDDCR_CPU0_P1_EN
J 0
(-7300 2660);
DISPLAY 0.489362 (-7300 2660);
WIRE 16 -1 (-6600 2500)(-7425 2500);
FORCEPROP 2 LAST SIG_NAME UART_LS_EN
J 0
(-7310 2510);
DISPLAY 0.446809 (-7310 2510);
WIRE 16 -1 (-6600 2450)(-7425 2450);
FORCEPROP 2 LAST SIG_NAME PWRGD_PVDDCR_CPU1_P1
J 0
(-7300 2460);
DISPLAY 0.489362 (-7300 2460);
WIRE 16 -1 (-6600 2300)(-7425 2300);
FORCEPROP 2 LAST SIG_NAME PWRGD_PVDDCR_CPU0_P1
J 0
(-7300 2310);
DISPLAY 0.489362 (-7300 2310);
WIRE 16 -1 (-6600 2850)(-7425 2850);
FORCEPROP 2 LAST SIG_NAME PWRGD_PVDDIO_P0
J 0
(-7300 2860);
DISPLAY 0.489362 (-7300 2860);
WIRE 16 -1 (-7425 2950)(-6600 2950);
FORCEPROP 2 LAST SIG_NAME PRSNT1_SLOT2_N
J 0
(-7300 2960);
DISPLAY 0.489362 (-7300 2960);
WIRE 16 -1 (-6600 2900)(-7425 2900);
FORCEPROP 2 LAST SIG_NAME PVDDIO_P0_EN
J 0
(-7300 2910);
DISPLAY 0.489362 (-7300 2910);
WIRE 16 -1 (-7225 6000)(-5400 6000);
FORCEPROP 2 LAST SIG_NAME FM_CPU0_SLP_S5_N
J 0
(-7050 6010);
DISPLAY 0.489362 (-7050 6010);
WIRE 16 -1 (-3250 5600)(-4100 5600);
FORCEPROP 2 LAST SIG_NAME BIOS_DEBUG_MODE_R
J 0
(-3985 5610);
DISPLAY 0.489362 (-3985 5610);
FORCEPROP 2 LASTPROP $XRERR UNIQUE?
J 0
(-4225 5610);
DISPLAY 0.638298 (-4225 5610);
PAINT MONO (-4225 5610);
DISPLAY INVISIBLE (-4225 5610);
WIRE 16 -1 (-4100 4900)(-3250 4900);
FORCEPROP 2 LAST SIG_NAME FM_HDT_HDR_RESET_N
J 0
(-3985 4910);
DISPLAY 0.489362 (-3985 4910);
FORCEPROP 2 LASTPROP $XRERR UNIQUE?
J 0
(-4225 4910);
DISPLAY 0.638298 (-4225 4910);
PAINT MONO (-4225 4910);
DISPLAY INVISIBLE (-4225 4910);
WIRE 16 -1 (-4100 5100)(-3250 5100);
FORCEPROP 2 LAST SIG_NAME ESPI_CPU0_R1_D1
J 0
(-3985 5110);
DISPLAY 0.446809 (-3985 5110);
FORCEPROP 2 LASTPROP $XRERR UNIQUE?
J 0
(-4225 5110);
DISPLAY 0.638298 (-4225 5110);
PAINT MONO (-4225 5110);
DISPLAY INVISIBLE (-4225 5110);
WIRE 16 -1 (-4100 5050)(-3250 5050);
FORCEPROP 2 LAST SIG_NAME ESPI_CPU0_R1_D2
J 0
(-3985 5060);
DISPLAY 0.446809 (-3985 5060);
FORCEPROP 2 LASTPROP $XRERR UNIQUE?
J 0
(-4225 5060);
DISPLAY 0.638298 (-4225 5060);
PAINT MONO (-4225 5060);
DISPLAY INVISIBLE (-4225 5060);
WIRE 16 -1 (-4100 5000)(-3250 5000);
FORCEPROP 2 LAST SIG_NAME ESPI_CPU0_R1_D3
J 0
(-3985 5010);
DISPLAY 0.446809 (-3985 5010);
FORCEPROP 2 LASTPROP $XRERR UNIQUE?
J 0
(-4225 5010);
DISPLAY 0.638298 (-4225 5010);
PAINT MONO (-4225 5010);
DISPLAY INVISIBLE (-4225 5010);
WIRE 16 -1 (-4100 4950)(-3250 4950);
FORCEPROP 2 LAST SIG_NAME FM_HDT_HDR_PWROK
J 0
(-3985 4960);
DISPLAY 0.489362 (-3985 4960);
FORCEPROP 2 LASTPROP $XRERR UNIQUE?
J 0
(-4225 4960);
DISPLAY 0.638298 (-4225 4960);
PAINT MONO (-4225 4960);
DISPLAY INVISIBLE (-4225 4960);
WIRE 16 -1 (-7225 4950)(-6450 4950);
FORCEPROP 2 LAST SIG_NAME RST_CPU1_RESETL_N
J 0
(-7050 4960);
DISPLAY 0.489362 (-7050 4960);
WIRE 16 -1 (-7225 4550)(-6450 4550);
FORCEPROP 2 LAST SIG_NAME CPU0_CLK_STRAP_SEL
J 0
(-7050 4560);
DISPLAY 0.489362 (-7050 4560);
WIRE 16 -1 (-6450 4600)(-7225 4600);
FORCEPROP 2 LAST SIG_NAME CPU0_NMI_SYNC_FLOOD_N
J 0
(-7050 4610);
DISPLAY 0.489362 (-7050 4610);
WIRE 16 -1 (-5400 4650)(-7225 4650);
FORCEPROP 2 LAST SIG_NAME PVDD11_S3_P1_RESET_N
J 0
(-7050 4660);
DISPLAY 0.489362 (-7050 4660);
WIRE 16 -1 (-6450 4750)(-7225 4750);
FORCEPROP 2 LAST SIG_NAME CPU1_NV_SAVE_N
J 0
(-7050 4760);
DISPLAY 0.489362 (-7050 4760);
WIRE 16 -1 (-7225 4800)(-6450 4800);
FORCEPROP 2 LAST SIG_NAME PWRGD_CPU0_PWROK
J 0
(-7050 4810);
DISPLAY 0.489362 (-7050 4810);
WIRE 16 -1 (-7225 4900)(-6450 4900);
FORCEPROP 2 LAST SIG_NAME RST_CPU0_KBRST_R_N
J 0
(-7050 4910);
DISPLAY 0.489362 (-7050 4910);
WIRE 16 -1 (-6450 4850)(-7225 4850);
FORCEPROP 2 LAST SIG_NAME CPU0_JTAG_BUF_OE
J 0
(-7060 4860);
DISPLAY 0.446809 (-7060 4860);
WIRE 16 -1 (-7225 5150)(-6450 5150);
FORCEPROP 2 LAST SIG_NAME CPU0_NV_SAVE_N
J 0
(-7050 5160);
DISPLAY 0.489362 (-7050 5160);
WIRE 16 -1 (-6450 5200)(-7225 5200);
FORCEPROP 2 LAST SIG_NAME RST_CPU1_SYS_N
J 0
(-7050 5210);
DISPLAY 0.489362 (-7050 5210);
WIRE 16 -1 (-6450 5250)(-7225 5250);
FORCEPROP 2 LAST SIG_NAME RST_CPU0_SYS_N
J 0
(-7050 5260);
DISPLAY 0.489362 (-7050 5260);
WIRE 16 -1 (-7225 5350)(-6450 5350);
FORCEPROP 2 LAST SIG_NAME RST_CPU0_RSMRST_N
J 0
(-7050 5360);
DISPLAY 0.489362 (-7050 5360);
WIRE 16 -1 (-7225 5400)(-6450 5400);
FORCEPROP 2 LAST SIG_NAME RST_CPU1_RSMRST_N
J 0
(-7050 5410);
DISPLAY 0.489362 (-7050 5410);
WIRE 16 -1 (-5400 4750)(-6250 4750);
FORCEPROP 2 LAST SIG_NAME FM_CPU1_NV_SAVE_N
J 0
(-6100 4760);
DISPLAY 0.489362 (-6100 4760);
FORCEPROP 2 LASTPROP $XRERR UNIQUE?
J 0
(-6340 4760);
DISPLAY 0.638298 (-6340 4760);
PAINT MONO (-6340 4760);
DISPLAY INVISIBLE (-6340 4760);
WIRE 16 -1 (-3050 5600)(-2275 5600);
FORCEPROP 2 LAST SIG_NAME BIOS_DEBUG_MODE
J 0
(-2875 5610);
DISPLAY 0.489362 (-2875 5610);
WIRE 16 -1 (-5400 4450)(-6250 4450);
FORCEPROP 2 LAST SIG_NAME FM_P1_PCC0_R_N
J 0
(-6100 4460);
DISPLAY 0.489362 (-6100 4460);
FORCEPROP 2 LASTPROP $XRERR UNIQUE?
J 0
(-6340 4460);
DISPLAY 0.638298 (-6340 4460);
PAINT MONO (-6340 4460);
DISPLAY INVISIBLE (-6340 4460);
WIRE 16 -1 (-5400 4500)(-6250 4500);
FORCEPROP 2 LAST SIG_NAME FM_PWRGD_CPU1_PWROK
J 0
(-6100 4510);
DISPLAY 0.489362 (-6100 4510);
FORCEPROP 2 LASTPROP $XRERR UNIQUE?
J 0
(-6340 4510);
DISPLAY 0.638298 (-6340 4510);
PAINT MONO (-6340 4510);
DISPLAY INVISIBLE (-6340 4510);
WIRE 16 -1 (-6250 4550)(-5400 4550);
FORCEPROP 2 LAST SIG_NAME FM_CPU0_CLK_STRAP_SEL
J 0
(-6100 4560);
DISPLAY 0.489362 (-6100 4560);
FORCEPROP 2 LASTPROP $XRERR UNIQUE?
J 0
(-6340 4560);
DISPLAY 0.638298 (-6340 4560);
PAINT MONO (-6340 4560);
DISPLAY INVISIBLE (-6340 4560);
WIRE 16 -1 (-3050 5950)(-2275 5950);
FORCEPROP 2 LAST SIG_NAME CPU0_SMERR_N
J 0
(-2875 5960);
DISPLAY 0.489362 (-2875 5960);
WIRE 16 -1 (-3050 6000)(-2275 6000);
FORCEPROP 2 LAST SIG_NAME FM_SMERR_LED_N
J 0
(-2875 6010);
DISPLAY 0.489362 (-2875 6010);
WIRE 16 -1 (-6450 5500)(-7225 5500);
FORCEPROP 2 LAST SIG_NAME RST_CPU1_PERST0_N
J 0
(-7050 5510);
DISPLAY 0.489362 (-7050 5510);
WIRE 16 -1 (-7225 5000)(-6450 5000);
FORCEPROP 2 LAST SIG_NAME RST_CPU0_RESETL_N
J 0
(-7050 5010);
DISPLAY 0.489362 (-7050 5010);
WIRE 16 -1 (-6450 5850)(-7225 5850);
FORCEPROP 2 LAST SIG_NAME RST_CPU1_PERST1_N
J 0
(-7050 5860);
DISPLAY 0.489362 (-7050 5860);
WIRE 16 -1 (-7225 5650)(-6450 5650);
FORCEPROP 2 LAST SIG_NAME RST_CPU0_PERST1_N
J 0
(-7050 5660);
DISPLAY 0.489362 (-7050 5660);
WIRE 16 -1 (-7225 4450)(-6450 4450);
FORCEPROP 2 LAST SIG_NAME FM_P1_PCC0_N
J 0
(-7050 4460);
DISPLAY 0.489362 (-7050 4460);
WIRE 16 -1 (-6450 4500)(-7225 4500);
FORCEPROP 2 LAST SIG_NAME PWRGD_CPU1_PWROK
J 0
(-7050 4510);
DISPLAY 0.489362 (-7050 4510);
WIRE 16 -1 (-7225 5900)(-6450 5900);
FORCEPROP 2 LAST SIG_NAME RST_CPU0_PERST0_N
J 0
(-7050 5910);
DISPLAY 0.489362 (-7050 5910);
WIRE 16 -1 (-6450 4150)(-7225 4150);
FORCEPROP 2 LAST SIG_NAME FM_P0_PCC1_N
J 0
(-7050 4160);
DISPLAY 0.489362 (-7050 4160);
WIRE 16 -1 (-6450 4350)(-7225 4350);
FORCEPROP 2 LAST SIG_NAME CPU0_PWR_BTN_N
J 0
(-7050 4360);
DISPLAY 0.489362 (-7050 4360);
WIRE 16 -1 (-6450 3950)(-7225 3950);
FORCEPROP 2 LAST SIG_NAME CPU1_SPD_HOST_CTRL_N
J 0
(-7050 3960);
DISPLAY 0.489362 (-7050 3960);
WIRE 16 -1 (-7225 4300)(-6450 4300);
FORCEPROP 2 LAST SIG_NAME FM_P1_PCC1_N
J 0
(-7050 4310);
DISPLAY 0.489362 (-7050 4310);
WIRE 16 -1 (-3550 2350)(-2650 2350);
FORCEPROP 2 LAST SIG_NAME RST_PERST_SLOT1_1_R_N
J 0
(-3375 2355);
DISPLAY 0.489362 (-3375 2355);
FORCEPROP 2 LASTPROP $XRERR UNIQUE?
J 0
(-3615 2355);
DISPLAY 0.638298 (-3615 2355);
PAINT MONO (-3615 2355);
DISPLAY INVISIBLE (-3615 2355);
WIRE 16 -1 (-1425 1800)(-3550 1800);
FORCEPROP 2 LAST SIG_NAME SW_P12V_MEM_EN
J 0
(-3375 1805);
DISPLAY 0.489362 (-3375 1805);
WIRE 16 -1 (-2450 2350)(-1425 2350);
FORCEPROP 2 LAST SIG_NAME RST_PERST_SLOT1_1_N
J 0
(-2130 2360);
DISPLAY 0.489362 (-2130 2360);
WIRE 16 -1 (-1425 2450)(-2450 2450);
FORCEPROP 2 LAST SIG_NAME P12V_E1S_4_EN_R
J 0
(-2130 2460);
DISPLAY 0.489362 (-2130 2460);
WIRE 16 -1 (-2450 2650)(-1425 2650);
FORCEPROP 2 LAST SIG_NAME PRSNT2_SLOT2_N
J 0
(-2135 2660);
DISPLAY 0.446809 (-2135 2660);
WIRE 16 -1 (-2450 2600)(-1425 2600);
FORCEPROP 2 LAST SIG_NAME FM_RST_PERST_SCM_N
J 0
(-2130 2610);
DISPLAY 0.489362 (-2130 2610);
WIRE 16 -1 (-2450 2550)(-1425 2550);
FORCEPROP 2 LAST SIG_NAME RST_PERST_E1S_1_N
J 0
(-2130 2560);
DISPLAY 0.489362 (-2130 2560);
WIRE 16 -1 (-1425 2500)(-2450 2500);
FORCEPROP 2 LAST SIG_NAME P12V_E1S_3_EN_R
J 0
(-2130 2510);
DISPLAY 0.489362 (-2130 2510);
WIRE 16 -1 (-1425 2700)(-2450 2700);
FORCEPROP 2 LAST SIG_NAME P3V3_E1S_2_EN_R
J 0
(-2130 2710);
DISPLAY 0.489362 (-2130 2710);
WIRE 16 -1 (-2450 2750)(-1425 2750);
FORCEPROP 2 LAST SIG_NAME PSU1_PS_ON_N
J 0
(-2130 2760);
DISPLAY 0.489362 (-2130 2760);
WIRE 16 -1 (-2450 2800)(-1425 2800);
FORCEPROP 2 LAST SIG_NAME PRSNT2_SLOT1_N
J 0
(-2135 2810);
DISPLAY 0.446809 (-2135 2810);
WIRE 16 -1 (-1425 2300)(-2450 2300);
FORCEPROP 2 LAST SIG_NAME RST_PERST_E1S_3_N
J 0
(-2130 2310);
DISPLAY 0.489362 (-2130 2310);
WIRE 16 -1 (-2650 2300)(-3550 2300);
FORCEPROP 2 LAST SIG_NAME RST_PERST_E1S_3_R_N
J 0
(-3375 2305);
DISPLAY 0.489362 (-3375 2305);
FORCEPROP 2 LASTPROP $XRERR UNIQUE?
J 0
(-3615 2305);
DISPLAY 0.638298 (-3615 2305);
PAINT MONO (-3615 2305);
DISPLAY INVISIBLE (-3615 2305);
WIRE 16 -1 (-3550 2450)(-2650 2450);
FORCEPROP 2 LAST SIG_NAME P12V_E1S_4_EN
J 0
(-3375 2460);
DISPLAY 0.489362 (-3375 2460);
FORCEPROP 2 LASTPROP $XRERR UNIQUE?
J 0
(-3615 2460);
DISPLAY 0.638298 (-3615 2460);
PAINT MONO (-3615 2460);
DISPLAY INVISIBLE (-3615 2460);
WIRE 16 -1 (-3550 2500)(-2650 2500);
FORCEPROP 2 LAST SIG_NAME P12V_E1S_3_EN
J 0
(-3375 2510);
DISPLAY 0.489362 (-3375 2510);
FORCEPROP 2 LASTPROP $XRERR UNIQUE?
J 0
(-3615 2510);
DISPLAY 0.638298 (-3615 2510);
PAINT MONO (-3615 2510);
DISPLAY INVISIBLE (-3615 2510);
WIRE 16 -1 (-2650 1200)(-3550 1200);
FORCEPROP 2 LAST SIG_NAME RST_PERST_SLOT3_R_N
J 0
(-3375 1205);
DISPLAY 0.489362 (-3375 1205);
FORCEPROP 2 LASTPROP $XRERR UNIQUE?
J 0
(-3615 1205);
DISPLAY 0.638298 (-3615 1205);
PAINT MONO (-3615 1205);
DISPLAY INVISIBLE (-3615 1205);
WIRE 16 -1 (-3550 1100)(-2650 1100);
FORCEPROP 0 LAST SIG_NAME FM_FPGA_SR_FAN_PWM_SEL
J 0
(-3375 1105);
DISPLAY 0.489362 (-3375 1105);
FORCEPROP 2 LASTPROP $XRERR UNIQUE?
J 0
(-3615 1105);
DISPLAY 0.638298 (-3615 1105);
PAINT MONO (-3615 1105);
DISPLAY INVISIBLE (-3615 1105);
WIRE 16 -1 (-2650 1300)(-3550 1300);
FORCEPROP 2 LAST SIG_NAME RST_PERST_M2_2_R_N
J 0
(-3375 1305);
DISPLAY 0.489362 (-3375 1305);
FORCEPROP 2 LASTPROP $XRERR UNIQUE?
J 0
(-3615 1305);
DISPLAY 0.638298 (-3615 1305);
PAINT MONO (-3615 1305);
DISPLAY INVISIBLE (-3615 1305);
WIRE 16 -1 (-2650 1450)(-3550 1450);
FORCEPROP 2 LAST SIG_NAME RST_PERST_M2_1_R_N
J 0
(-3375 1455);
DISPLAY 0.489362 (-3375 1455);
FORCEPROP 2 LASTPROP $XRERR UNIQUE?
J 0
(-3615 1455);
DISPLAY 0.638298 (-3615 1455);
PAINT MONO (-3615 1455);
DISPLAY INVISIBLE (-3615 1455);
WIRE 16 -1 (-2650 1850)(-3550 1850);
FORCEPROP 0 LAST SIG_NAME FM_E1S_4_R_PWRDIS
J 0
(-3375 1860);
DISPLAY 0.489362 (-3375 1860);
FORCEPROP 2 LASTPROP $XRERR UNIQUE?
J 0
(-3615 1860);
DISPLAY 0.638298 (-3615 1860);
PAINT MONO (-3615 1860);
DISPLAY INVISIBLE (-3615 1860);
WIRE 16 -1 (-1425 1750)(-3550 1750);
FORCEPROP 2 LAST SIG_NAME SW_P12V_EN
J 0
(-3375 1755);
DISPLAY 0.489362 (-3375 1755);
WIRE 16 -1 (-2650 1700)(-3550 1700);
FORCEPROP 2 LAST SIG_NAME RST_PERST_E1S_4_R_N
J 0
(-3375 1705);
DISPLAY 0.489362 (-3375 1705);
FORCEPROP 2 LASTPROP $XRERR UNIQUE?
J 0
(-3615 1705);
DISPLAY 0.638298 (-3615 1705);
PAINT MONO (-3615 1705);
DISPLAY INVISIBLE (-3615 1705);
WIRE 16 -1 (-1425 1200)(-2450 1200);
FORCEPROP 2 LAST SIG_NAME RST_PERST_SLOT3_N
J 0
(-2130 1210);
DISPLAY 0.489362 (-2130 1210);
WIRE 16 -1 (-2450 1100)(-1425 1100);
FORCEPROP 0 LAST SIG_NAME FPGA_SR_FAN_PWM_SEL
J 0
(-2130 1110);
DISPLAY 0.489362 (-2130 1110);
WIRE 16 -1 (-2650 1900)(-3550 1900);
FORCEPROP 0 LAST SIG_NAME FM_E1S_3_R_PWRDIS
J 0
(-3375 1910);
DISPLAY 0.489362 (-3375 1910);
FORCEPROP 2 LASTPROP $XRERR UNIQUE?
J 0
(-3615 1910);
DISPLAY 0.638298 (-3615 1910);
PAINT MONO (-3615 1910);
DISPLAY INVISIBLE (-3615 1910);
WIRE 16 -1 (-1425 1850)(-2450 1850);
FORCEPROP 0 LAST SIG_NAME FM_E1S_4_PWRDIS
J 0
(-2130 1860);
DISPLAY 0.489362 (-2130 1860);
WIRE 16 -1 (-1425 2150)(-2450 2150);
FORCEPROP 2 LAST SIG_NAME RST_SMBMUX_U8_N
J 0
(-2130 2160);
DISPLAY 0.489362 (-2130 2160);
WIRE 16 -1 (-1425 2100)(-2450 2100);
FORCEPROP 2 LAST SIG_NAME P3V3_E1S_3_EN_R
J 0
(-2130 2110);
DISPLAY 0.489362 (-2130 2110);
WIRE 16 -1 (-1425 2050)(-2450 2050);
FORCEPROP 2 LAST SIG_NAME P3V3_E1S_4_EN_R
J 0
(-2130 2060);
DISPLAY 0.489362 (-2130 2060);
WIRE 16 -1 (-3550 2000)(-1425 2000);
FORCEPROP 2 LAST SIG_NAME P12V_E1S_4_PWRGD
J 0
(-3375 2010);
DISPLAY 0.489362 (-3375 2010);
WIRE 16 -1 (-3550 1950)(-1425 1950);
FORCEPROP 2 LAST SIG_NAME PWGD_P3V3_E1S_4
J 0
(-3375 1960);
DISPLAY 0.489362 (-3375 1960);
WIRE 16 -1 (-1425 1900)(-2450 1900);
FORCEPROP 0 LAST SIG_NAME FM_E1S_3_PWRDIS
J 0
(-2130 1910);
DISPLAY 0.489362 (-2130 1910);
WIRE 16 -1 (-1425 2200)(-2450 2200);
FORCEPROP 2 LAST SIG_NAME RST_SMBMUX_U7_N
J 0
(-2130 2210);
DISPLAY 0.489362 (-2130 2210);
WIRE 16 -1 (-2450 2250)(-1425 2250);
FORCEPROP 2 LAST SIG_NAME RST_PERST_E1S_2_N
J 0
(-2130 2260);
DISPLAY 0.489362 (-2130 2260);
WIRE 16 -1 (-3550 2150)(-2650 2150);
FORCEPROP 2 LAST SIG_NAME RST_SMBMUX_U8_R_N
J 0
(-3375 2155);
DISPLAY 0.489362 (-3375 2155);
FORCEPROP 2 LASTPROP $XRERR UNIQUE?
J 0
(-3615 2155);
DISPLAY 0.638298 (-3615 2155);
PAINT MONO (-3615 2155);
DISPLAY INVISIBLE (-3615 2155);
WIRE 16 -1 (-3550 2250)(-2650 2250);
FORCEPROP 2 LAST SIG_NAME RST_PERST_E1S_2_R_N
J 0
(-3375 2255);
DISPLAY 0.489362 (-3375 2255);
FORCEPROP 2 LASTPROP $XRERR UNIQUE?
J 0
(-3615 2255);
DISPLAY 0.638298 (-3615 2255);
PAINT MONO (-3615 2255);
DISPLAY INVISIBLE (-3615 2255);
WIRE 16 -1 (-6450 4100)(-7225 4100);
FORCEPROP 2 LAST SIG_NAME FM_P0_PCC0_N
J 0
(-7050 4110);
DISPLAY 0.489362 (-7050 4110);
WIRE 16 -1 (-3550 850)(-2650 850);
FORCEPROP 2 LAST SIG_NAME RST_PERST_SLOT1_0_R_N
J 0
(-3375 855);
DISPLAY 0.489362 (-3375 855);
FORCEPROP 2 LASTPROP $XRERR UNIQUE?
J 0
(-3615 855);
DISPLAY 0.638298 (-3615 855);
PAINT MONO (-3615 855);
DISPLAY INVISIBLE (-3615 855);
WIRE 16 -1 (-2650 900)(-3550 900);
FORCEPROP 2 LAST SIG_NAME RST_PERST_SLOT2_1_R_N
J 0
(-3375 905);
DISPLAY 0.489362 (-3375 905);
FORCEPROP 2 LASTPROP $XRERR UNIQUE?
J 0
(-3615 905);
DISPLAY 0.638298 (-3615 905);
PAINT MONO (-3615 905);
DISPLAY INVISIBLE (-3615 905);
WIRE 16 -1 (-3550 650)(-2650 650);
FORCEPROP 0 LAST SIG_NAME FM_FPGA_DR_FAN_PWM_SEL
J 0
(-3375 655);
DISPLAY 0.489362 (-3375 655);
FORCEPROP 2 LASTPROP $XRERR UNIQUE?
J 0
(-3615 655);
DISPLAY 0.638298 (-3615 655);
PAINT MONO (-3615 655);
DISPLAY INVISIBLE (-3615 655);
WIRE 16 -1 (-3550 2050)(-2650 2050);
FORCEPROP 2 LAST SIG_NAME P3V3_E1S_4_EN
J 0
(-3375 2060);
DISPLAY 0.489362 (-3375 2060);
FORCEPROP 2 LASTPROP $XRERR UNIQUE?
J 0
(-3615 2060);
DISPLAY 0.638298 (-3615 2060);
PAINT MONO (-3615 2060);
DISPLAY INVISIBLE (-3615 2060);
WIRE 16 -1 (-3550 2100)(-2650 2100);
FORCEPROP 2 LAST SIG_NAME P3V3_E1S_3_EN
J 0
(-3375 2110);
DISPLAY 0.489362 (-3375 2110);
FORCEPROP 2 LASTPROP $XRERR UNIQUE?
J 0
(-3615 2110);
DISPLAY 0.638298 (-3615 2110);
PAINT MONO (-3615 2110);
DISPLAY INVISIBLE (-3615 2110);
WIRE 16 -1 (-2450 650)(-1425 650);
FORCEPROP 0 LAST SIG_NAME FPGA_DR_FAN_PWM_SEL
J 0
(-2130 660);
DISPLAY 0.489362 (-2130 660);
WIRE 16 -1 (-2450 850)(-1425 850);
FORCEPROP 2 LAST SIG_NAME RST_PERST_SLOT1_0_N
J 0
(-2130 860);
DISPLAY 0.489362 (-2130 860);
WIRE 16 -1 (-1425 900)(-2450 900);
FORCEPROP 2 LAST SIG_NAME RST_PERST_SLOT2_1_N
J 0
(-2130 910);
DISPLAY 0.489362 (-2130 910);
FORCENOTE
BANK2 P3V3_STBY
(-4325 3150) 0;
DISPLAY LEFT (-4325 3150);
DISPLAY 3.148936 (-4325 3150);
FORCENOTE
BANK1 P1V8_STBY
(-4650 6175) 0;
DISPLAY LEFT (-4650 6175);
DISPLAY 3.148936 (-4650 6175);
QUIT
